G04 ================== begin FILE IDENTIFICATION RECORD ==================*
G04 Layout Name:  D:/<user>/Wistron_project/16318-2/gbr/16318-2.brd*
G04 Film Name:    DP_REF_L8*
G04 File Format:  Gerber RS274X*
G04 File Origin:  Cadence Allegro 16.5-S056*
G04 Origin Date:  Mon Aug 07 11:10:03 2017*
G04 *
G04 Layer:  BOARD GEOMETRY/DP_REF_L8_TBL*
G04 Layer:  BOARD GEOMETRY/DP_REF_L8_BOTTOM*
G04 Layer:  BOARD GEOMETRY/PANEL_OUTLINE*
G04 *
G04 Offset:    (0.00 0.00)*
G04 Mirror:    No*
G04 Mode:      Positive*
G04 Rotation:  0*
G04 FullContactRelief:  No*
G04 UndefLineWidth:     6.00*
G04 ================== end FILE IDENTIFICATION RECORD ====================*
%FSLAX35Y35*MOIN*%
%IR0*IPPOS*OFA0.00000B0.00000*MIA0B0*SFA1.00000B1.00000*%
%ADD10C,.02*%
%ADD11C,.006*%
%ADD12C,.0049*%
%ADD13C,.00575*%
G75*
%LPD*%
G75*
G54D10*
G01X975497Y590830D02*
X1727997D01*
G01X975497Y556180D02*
X1727997D01*
G01X975497Y729430D02*
Y556180D01*
G01Y625480D02*
X1727997D01*
G01X975497Y694780D02*
X1727997D01*
G01X975497Y660130D02*
X1727997D01*
G01X975497Y729430D02*
X1727997D01*
G01X1150497D02*
Y556180D01*
G01X1412997Y729430D02*
Y556180D01*
G01X1517997Y729430D02*
Y556180D01*
G01X1727997Y729430D02*
Y556180D01*
G54D11*
G01X6250Y-32800D02*
Y-50300D01*
G01X1228Y-32800D02*
X11272D01*
G01X20038Y-50300D02*
Y-32800D01*
G01Y-41258D02*
X21130Y-39800D01*
X22222Y-38925D01*
X23968Y-38634D01*
X25278Y-38925D01*
X26807Y-40092D01*
X27462Y-41842D01*
Y-50300D01*
G01X41250Y-38634D02*
Y-50300D01*
G01Y-33967D02*
X40813Y-33675D01*
Y-33092D01*
X41250Y-32800D01*
X41687Y-33092D01*
Y-33675D01*
X41250Y-33967D01*
G01X55475Y-48259D02*
X56567Y-49425D01*
X58095Y-50300D01*
X59405D01*
X60715Y-49717D01*
X61588Y-48842D01*
X62025Y-47676D01*
X61807Y-45925D01*
X60933Y-45050D01*
X57003Y-43300D01*
X56130Y-41258D01*
X56567Y-39800D01*
X57440Y-38925D01*
X58750Y-38634D01*
X60060Y-38925D01*
X61370Y-39800D01*
G01X90693Y-54675D02*
X92222Y-55842D01*
X93968Y-56133D01*
X95496Y-55842D01*
X96807Y-54384D01*
X97680Y-52342D01*
Y-38634D01*
G01Y-40967D02*
X96807Y-39800D01*
X95496Y-38925D01*
X93968Y-38634D01*
X92222Y-39217D01*
X91130Y-40383D01*
X90256Y-42425D01*
X89820Y-44467D01*
X90038Y-46217D01*
X90912Y-48259D01*
X92222Y-49717D01*
X93968Y-50300D01*
X95278Y-50008D01*
X96807Y-48842D01*
X97680Y-47676D01*
G01X107975Y-42425D02*
X114962D01*
X114307Y-40383D01*
X113215Y-39217D01*
X111687Y-38634D01*
X110158Y-38925D01*
X108848Y-39800D01*
X107975Y-41842D01*
X107538Y-43592D01*
Y-45342D01*
X107975Y-47092D01*
X109067Y-48842D01*
X110377Y-50008D01*
X111905Y-50300D01*
X113433Y-49717D01*
X114962Y-47967D01*
G01X125693Y-50300D02*
Y-38634D01*
G01Y-40967D02*
X126785Y-39800D01*
X127877Y-38925D01*
X129405Y-38634D01*
X130496Y-38925D01*
X131807Y-39800D01*
G01X142320Y-50300D02*
Y-32800D01*
G01Y-41550D02*
X143412Y-39800D01*
X144722Y-38925D01*
X146032Y-38634D01*
X147996Y-39217D01*
X149307Y-40383D01*
X150180Y-42425D01*
Y-44758D01*
X149743Y-47092D01*
X148870Y-48842D01*
X147342Y-50008D01*
X146032Y-50300D01*
X144722Y-50008D01*
X143412Y-49134D01*
X142320Y-47676D01*
G01X160475Y-42425D02*
X167462D01*
X166807Y-40383D01*
X165715Y-39217D01*
X164187Y-38634D01*
X162658Y-38925D01*
X161348Y-39800D01*
X160475Y-41842D01*
X160038Y-43592D01*
Y-45342D01*
X160475Y-47092D01*
X161567Y-48842D01*
X162877Y-50008D01*
X164405Y-50300D01*
X165933Y-49717D01*
X167462Y-47967D01*
G01X178193Y-50300D02*
Y-38634D01*
G01Y-40967D02*
X179285Y-39800D01*
X180377Y-38925D01*
X181905Y-38634D01*
X182996Y-38925D01*
X184307Y-39800D01*
G01X216250Y-38634D02*
Y-50300D01*
G01Y-33967D02*
X215813Y-33675D01*
Y-33092D01*
X216250Y-32800D01*
X216687Y-33092D01*
Y-33675D01*
X216250Y-33967D01*
G01X230475Y-48259D02*
X231567Y-49425D01*
X233095Y-50300D01*
X234405D01*
X235715Y-49717D01*
X236588Y-48842D01*
X237025Y-47676D01*
X236807Y-45925D01*
X235933Y-45050D01*
X232003Y-43300D01*
X231130Y-41258D01*
X231567Y-39800D01*
X232440Y-38925D01*
X233750Y-38634D01*
X235060Y-38925D01*
X236370Y-39800D01*
G01X265256Y-54675D02*
X266785Y-55842D01*
X268095Y-56133D01*
X269842Y-55550D01*
X271152Y-54092D01*
X271807Y-51466D01*
Y-38634D01*
G01Y-33967D02*
X271370Y-33675D01*
Y-33092D01*
X271807Y-32800D01*
X272243Y-33092D01*
Y-33675D01*
X271807Y-33967D01*
G01X282538Y-38634D02*
Y-46800D01*
X283412Y-48842D01*
X284722Y-50008D01*
X286250Y-50300D01*
X287778Y-50008D01*
X289088Y-48842D01*
X289962Y-46800D01*
G01Y-50300D02*
Y-38634D01*
G01X300475Y-48259D02*
X301567Y-49425D01*
X303095Y-50300D01*
X304405D01*
X305715Y-49717D01*
X306588Y-48842D01*
X307025Y-47676D01*
X306807Y-45925D01*
X305933Y-45050D01*
X302003Y-43300D01*
X301130Y-41258D01*
X301567Y-39800D01*
X302440Y-38925D01*
X303750Y-38634D01*
X305060Y-38925D01*
X306370Y-39800D01*
G01X321250Y-32800D02*
Y-50300D01*
G01X318193Y-38634D02*
X324307D01*
G01X354940Y-50300D02*
Y-35425D01*
X355377Y-33967D01*
X356250Y-33092D01*
X357560Y-32800D01*
X358870Y-33383D01*
X359525Y-34842D01*
G01X356905Y-39800D02*
X352538D01*
G01X373750Y-50300D02*
X372440Y-50008D01*
X371130Y-48842D01*
X370256Y-46800D01*
X369820Y-44467D01*
X370256Y-42133D01*
X371130Y-40092D01*
X372440Y-38925D01*
X373750Y-38634D01*
X375060Y-38925D01*
X376370Y-40092D01*
X377243Y-42133D01*
X377462Y-44467D01*
X377243Y-46800D01*
X376370Y-48842D01*
X375060Y-50008D01*
X373750Y-50300D01*
G01X388193D02*
Y-38634D01*
G01Y-40967D02*
X389285Y-39800D01*
X390377Y-38925D01*
X391905Y-38634D01*
X392996Y-38925D01*
X394307Y-39800D01*
G01X421665Y-55550D02*
X422975Y-56133D01*
X424722Y-55550D01*
X425813Y-54384D01*
X426687Y-52925D01*
X427996Y-48259D01*
X430835Y-38634D01*
G01X423848D02*
X427996Y-48259D01*
G01X443750Y-50300D02*
X442440Y-50008D01*
X441130Y-48842D01*
X440256Y-46800D01*
X439820Y-44467D01*
X440256Y-42133D01*
X441130Y-40092D01*
X442440Y-38925D01*
X443750Y-38634D01*
X445060Y-38925D01*
X446370Y-40092D01*
X447243Y-42133D01*
X447462Y-44467D01*
X447243Y-46800D01*
X446370Y-48842D01*
X445060Y-50008D01*
X443750Y-50300D01*
G01X457538Y-38634D02*
Y-46800D01*
X458412Y-48842D01*
X459722Y-50008D01*
X461250Y-50300D01*
X462778Y-50008D01*
X464088Y-48842D01*
X464962Y-46800D01*
G01Y-50300D02*
Y-38634D01*
G01X475693Y-50300D02*
Y-38634D01*
G01Y-40967D02*
X476785Y-39800D01*
X477877Y-38925D01*
X479405Y-38634D01*
X480496Y-38925D01*
X481807Y-39800D01*
G01X510693Y-50300D02*
Y-38634D01*
G01Y-40967D02*
X511785Y-39800D01*
X512877Y-38925D01*
X514405Y-38634D01*
X515496Y-38925D01*
X516807Y-39800D01*
G01X527975Y-42425D02*
X534962D01*
X534307Y-40383D01*
X533215Y-39217D01*
X531687Y-38634D01*
X530158Y-38925D01*
X528848Y-39800D01*
X527975Y-41842D01*
X527538Y-43592D01*
Y-45342D01*
X527975Y-47092D01*
X529067Y-48842D01*
X530377Y-50008D01*
X531905Y-50300D01*
X533433Y-49717D01*
X534962Y-47967D01*
G01X547440Y-50300D02*
Y-35425D01*
X547877Y-33967D01*
X548750Y-33092D01*
X550060Y-32800D01*
X551370Y-33383D01*
X552025Y-34842D01*
G01X549405Y-39800D02*
X545038D01*
G01X562975Y-42425D02*
X569962D01*
X569307Y-40383D01*
X568215Y-39217D01*
X566687Y-38634D01*
X565158Y-38925D01*
X563848Y-39800D01*
X562975Y-41842D01*
X562538Y-43592D01*
Y-45342D01*
X562975Y-47092D01*
X564067Y-48842D01*
X565377Y-50008D01*
X566905Y-50300D01*
X568433Y-49717D01*
X569962Y-47967D01*
G01X580693Y-50300D02*
Y-38634D01*
G01Y-40967D02*
X581785Y-39800D01*
X582877Y-38925D01*
X584405Y-38634D01*
X585496Y-38925D01*
X586807Y-39800D01*
G01X597975Y-42425D02*
X604962D01*
X604307Y-40383D01*
X603215Y-39217D01*
X601687Y-38634D01*
X600158Y-38925D01*
X598848Y-39800D01*
X597975Y-41842D01*
X597538Y-43592D01*
Y-45342D01*
X597975Y-47092D01*
X599067Y-48842D01*
X600377Y-50008D01*
X601905Y-50300D01*
X603433Y-49717D01*
X604962Y-47967D01*
G01X615038Y-50300D02*
Y-38634D01*
G01Y-41550D02*
X615912Y-40092D01*
X617222Y-38925D01*
X618968Y-38634D01*
X620496Y-38925D01*
X621807Y-40092D01*
X622462Y-42133D01*
Y-50300D01*
G01X639743Y-40092D02*
X638215Y-38925D01*
X636905Y-38634D01*
X635158Y-39217D01*
X633848Y-40383D01*
X632975Y-42425D01*
X632756Y-44467D01*
X632975Y-46509D01*
X633848Y-48259D01*
X635158Y-49717D01*
X636905Y-50300D01*
X638433Y-49717D01*
X639743Y-48550D01*
G01X650475Y-42425D02*
X657462D01*
X656807Y-40383D01*
X655715Y-39217D01*
X654187Y-38634D01*
X652658Y-38925D01*
X651348Y-39800D01*
X650475Y-41842D01*
X650038Y-43592D01*
Y-45342D01*
X650475Y-47092D01*
X651567Y-48842D01*
X652877Y-50008D01*
X654405Y-50300D01*
X655933Y-49717D01*
X657462Y-47967D01*
G01X688750Y-32800D02*
Y-50300D01*
G01X685693Y-38634D02*
X691807D01*
G01X706250Y-50300D02*
X704940Y-50008D01*
X703630Y-48842D01*
X702756Y-46800D01*
X702320Y-44467D01*
X702756Y-42133D01*
X703630Y-40092D01*
X704940Y-38925D01*
X706250Y-38634D01*
X707560Y-38925D01*
X708870Y-40092D01*
X709743Y-42133D01*
X709962Y-44467D01*
X709743Y-46800D01*
X708870Y-48842D01*
X707560Y-50008D01*
X706250Y-50300D01*
G01X739940D02*
Y-35425D01*
X740377Y-33967D01*
X741250Y-33092D01*
X742560Y-32800D01*
X743870Y-33383D01*
X744525Y-34842D01*
G01X741905Y-39800D02*
X737538D01*
G01X758750Y-38634D02*
Y-50300D01*
G01Y-33967D02*
X758313Y-33675D01*
Y-33092D01*
X758750Y-32800D01*
X759187Y-33092D01*
Y-33675D01*
X758750Y-33967D01*
G01X772538Y-50300D02*
Y-38634D01*
G01Y-41550D02*
X773412Y-40092D01*
X774722Y-38925D01*
X776468Y-38634D01*
X777996Y-38925D01*
X779307Y-40092D01*
X779962Y-42133D01*
Y-50300D01*
G01X797680Y-32800D02*
Y-50300D01*
G01Y-47676D02*
X796807Y-49134D01*
X795496Y-50008D01*
X793968Y-50300D01*
X792222Y-49717D01*
X790912Y-48259D01*
X790038Y-46509D01*
X789820Y-44467D01*
X790038Y-42425D01*
X790912Y-40675D01*
X792222Y-39217D01*
X793968Y-38634D01*
X795496Y-38925D01*
X796588Y-39509D01*
X797680Y-40675D01*
G01X828750Y-32800D02*
Y-50300D01*
G01X825693Y-38634D02*
X831807D01*
G01X842538Y-50300D02*
Y-32800D01*
G01Y-41258D02*
X843630Y-39800D01*
X844722Y-38925D01*
X846468Y-38634D01*
X847778Y-38925D01*
X849307Y-40092D01*
X849962Y-41842D01*
Y-50300D01*
G01X860475Y-42425D02*
X867462D01*
X866807Y-40383D01*
X865715Y-39217D01*
X864187Y-38634D01*
X862658Y-38925D01*
X861348Y-39800D01*
X860475Y-41842D01*
X860038Y-43592D01*
Y-45342D01*
X860475Y-47092D01*
X861567Y-48842D01*
X862877Y-50008D01*
X864405Y-50300D01*
X865933Y-49717D01*
X867462Y-47967D01*
G01X893947Y-50300D02*
Y-32800D01*
X898313D01*
X900060Y-33675D01*
X901370Y-34842D01*
X902462Y-36591D01*
X903335Y-38634D01*
X903553Y-41550D01*
X903335Y-44467D01*
X902462Y-46509D01*
X901370Y-48259D01*
X900060Y-49425D01*
X898313Y-50300D01*
X893947D01*
G01X911883D02*
Y-32800D01*
X917123D01*
X918870Y-33675D01*
X920180Y-35717D01*
X920617Y-38050D01*
X920180Y-40383D01*
X919088Y-42133D01*
X917123Y-43009D01*
X911883D01*
G01X951250Y-38634D02*
Y-50300D01*
G01Y-33967D02*
X950813Y-33675D01*
Y-33092D01*
X951250Y-32800D01*
X951687Y-33092D01*
Y-33675D01*
X951250Y-33967D01*
G01X962200Y-50300D02*
Y-38634D01*
G01Y-41842D02*
X962855Y-40383D01*
X963947Y-39217D01*
X965475Y-38634D01*
X967003Y-39217D01*
X968095Y-40383D01*
X968750Y-41842D01*
Y-50300D01*
G01Y-41842D02*
X969405Y-40383D01*
X970496Y-39217D01*
X972025Y-38634D01*
X973553Y-39217D01*
X974645Y-40383D01*
X975300Y-42133D01*
Y-50300D01*
G01X982320Y-56133D02*
Y-38634D01*
G01Y-41258D02*
X983412Y-39800D01*
X984503Y-38925D01*
X986250Y-38634D01*
X987778Y-38925D01*
X989307Y-40383D01*
X989962Y-42425D01*
X990180Y-44467D01*
X989962Y-46509D01*
X989307Y-48550D01*
X987996Y-49717D01*
X986250Y-50300D01*
X984722Y-50008D01*
X983193Y-49134D01*
X982320Y-47967D01*
G01X1000475Y-42425D02*
X1007462D01*
X1006807Y-40383D01*
X1005715Y-39217D01*
X1004187Y-38634D01*
X1002658Y-38925D01*
X1001348Y-39800D01*
X1000475Y-41842D01*
X1000038Y-43592D01*
Y-45342D01*
X1000475Y-47092D01*
X1001567Y-48842D01*
X1002877Y-50008D01*
X1004405Y-50300D01*
X1005933Y-49717D01*
X1007462Y-47967D01*
G01X1025180Y-32800D02*
Y-50300D01*
G01Y-47676D02*
X1024307Y-49134D01*
X1022996Y-50008D01*
X1021468Y-50300D01*
X1019722Y-49717D01*
X1018412Y-48259D01*
X1017538Y-46509D01*
X1017320Y-44467D01*
X1017538Y-42425D01*
X1018412Y-40675D01*
X1019722Y-39217D01*
X1021468Y-38634D01*
X1022996Y-38925D01*
X1024088Y-39509D01*
X1025180Y-40675D01*
G01X1042680Y-50300D02*
Y-38634D01*
G01Y-40675D02*
X1041807Y-39509D01*
X1040496Y-38925D01*
X1038968Y-38634D01*
X1037440Y-39217D01*
X1036130Y-40383D01*
X1035256Y-42133D01*
X1034820Y-44467D01*
X1035256Y-46800D01*
X1036130Y-48550D01*
X1037440Y-49717D01*
X1038968Y-50300D01*
X1040496Y-50008D01*
X1041807Y-49134D01*
X1042680Y-47967D01*
G01X1052538Y-50300D02*
Y-38634D01*
G01Y-41550D02*
X1053412Y-40092D01*
X1054722Y-38925D01*
X1056468Y-38634D01*
X1057996Y-38925D01*
X1059307Y-40092D01*
X1059962Y-42133D01*
Y-50300D01*
G01X1077243Y-40092D02*
X1075715Y-38925D01*
X1074405Y-38634D01*
X1072658Y-39217D01*
X1071348Y-40383D01*
X1070475Y-42425D01*
X1070256Y-44467D01*
X1070475Y-46509D01*
X1071348Y-48259D01*
X1072658Y-49717D01*
X1074405Y-50300D01*
X1075933Y-49717D01*
X1077243Y-48550D01*
G01X1087975Y-42425D02*
X1094962D01*
X1094307Y-40383D01*
X1093215Y-39217D01*
X1091687Y-38634D01*
X1090158Y-38925D01*
X1088848Y-39800D01*
X1087975Y-41842D01*
X1087538Y-43592D01*
Y-45342D01*
X1087975Y-47092D01*
X1089067Y-48842D01*
X1090377Y-50008D01*
X1091905Y-50300D01*
X1093433Y-49717D01*
X1094962Y-47967D01*
G01X1126250Y-32800D02*
Y-50300D01*
G01X1123193Y-38634D02*
X1129307D01*
G01X1140693Y-50300D02*
Y-38634D01*
G01Y-40967D02*
X1141785Y-39800D01*
X1142877Y-38925D01*
X1144405Y-38634D01*
X1145496Y-38925D01*
X1146807Y-39800D01*
G01X1165180Y-50300D02*
Y-38634D01*
G01Y-40675D02*
X1164307Y-39509D01*
X1162996Y-38925D01*
X1161468Y-38634D01*
X1159940Y-39217D01*
X1158630Y-40383D01*
X1157756Y-42133D01*
X1157320Y-44467D01*
X1157756Y-46800D01*
X1158630Y-48550D01*
X1159940Y-49717D01*
X1161468Y-50300D01*
X1162996Y-50008D01*
X1164307Y-49134D01*
X1165180Y-47967D01*
G01X1182243Y-40092D02*
X1180715Y-38925D01*
X1179405Y-38634D01*
X1177658Y-39217D01*
X1176348Y-40383D01*
X1175475Y-42425D01*
X1175256Y-44467D01*
X1175475Y-46509D01*
X1176348Y-48259D01*
X1177658Y-49717D01*
X1179405Y-50300D01*
X1180933Y-49717D01*
X1182243Y-48550D01*
G01X1192975Y-42425D02*
X1199962D01*
X1199307Y-40383D01*
X1198215Y-39217D01*
X1196687Y-38634D01*
X1195158Y-38925D01*
X1193848Y-39800D01*
X1192975Y-41842D01*
X1192538Y-43592D01*
Y-45342D01*
X1192975Y-47092D01*
X1194067Y-48842D01*
X1195377Y-50008D01*
X1196905Y-50300D01*
X1198433Y-49717D01*
X1199962Y-47967D01*
G01X1210475Y-48259D02*
X1211567Y-49425D01*
X1213095Y-50300D01*
X1214405D01*
X1215715Y-49717D01*
X1216588Y-48842D01*
X1217025Y-47676D01*
X1216807Y-45925D01*
X1215933Y-45050D01*
X1212003Y-43300D01*
X1211130Y-41258D01*
X1211567Y-39800D01*
X1212440Y-38925D01*
X1213750Y-38634D01*
X1215060Y-38925D01*
X1216370Y-39800D01*
G01X1248750Y-38634D02*
Y-50300D01*
G01Y-33967D02*
X1248313Y-33675D01*
Y-33092D01*
X1248750Y-32800D01*
X1249187Y-33092D01*
Y-33675D01*
X1248750Y-33967D01*
G01X1262538Y-50300D02*
Y-38634D01*
G01Y-41550D02*
X1263412Y-40092D01*
X1264722Y-38925D01*
X1266468Y-38634D01*
X1267996Y-38925D01*
X1269307Y-40092D01*
X1269962Y-42133D01*
Y-50300D01*
G01X1301250D02*
Y-32800D01*
G01X1322680Y-50300D02*
Y-38634D01*
G01Y-40675D02*
X1321807Y-39509D01*
X1320496Y-38925D01*
X1318968Y-38634D01*
X1317440Y-39217D01*
X1316130Y-40383D01*
X1315256Y-42133D01*
X1314820Y-44467D01*
X1315256Y-46800D01*
X1316130Y-48550D01*
X1317440Y-49717D01*
X1318968Y-50300D01*
X1320496Y-50008D01*
X1321807Y-49134D01*
X1322680Y-47967D01*
G01X1331665Y-55550D02*
X1332975Y-56133D01*
X1334722Y-55550D01*
X1335813Y-54384D01*
X1336687Y-52925D01*
X1337996Y-48259D01*
X1340835Y-38634D01*
G01X1333848D02*
X1337996Y-48259D01*
G01X1350475Y-42425D02*
X1357462D01*
X1356807Y-40383D01*
X1355715Y-39217D01*
X1354187Y-38634D01*
X1352658Y-38925D01*
X1351348Y-39800D01*
X1350475Y-41842D01*
X1350038Y-43592D01*
Y-45342D01*
X1350475Y-47092D01*
X1351567Y-48842D01*
X1352877Y-50008D01*
X1354405Y-50300D01*
X1355933Y-49717D01*
X1357462Y-47967D01*
G01X1368193Y-50300D02*
Y-38634D01*
G01Y-40967D02*
X1369285Y-39800D01*
X1370377Y-38925D01*
X1371905Y-38634D01*
X1372996Y-38925D01*
X1374307Y-39800D01*
G01X1401883Y-32800D02*
Y-50300D01*
X1410617D01*
G01X1423750D02*
X1425278Y-50008D01*
X1427025Y-49134D01*
X1428117Y-47676D01*
X1428553Y-45633D01*
X1428117Y-43592D01*
X1426807Y-41842D01*
X1424842Y-40967D01*
X1422658D01*
X1421348Y-40383D01*
X1420256Y-38925D01*
X1419820Y-36884D01*
X1420475Y-34842D01*
X1422003Y-33383D01*
X1423750Y-32800D01*
X1425496Y-33383D01*
X1427025Y-34842D01*
X1427680Y-36884D01*
X1427243Y-38925D01*
X1426152Y-40383D01*
X1424842Y-40967D01*
X1422658D01*
X1420693Y-41842D01*
X1419383Y-43592D01*
X1418947Y-45633D01*
X1419383Y-47676D01*
X1420475Y-49134D01*
X1422222Y-50008D01*
X1423750Y-50300D01*
G01X1441250Y-50883D02*
X1440813Y-50592D01*
Y-50008D01*
X1441250Y-49717D01*
X1441687Y-50008D01*
Y-50592D01*
X1441250Y-50883D01*
G01X999127Y722030D02*
X1004367D01*
G01X1001747D02*
Y704530D01*
G01X999127D02*
X1004367D01*
G01X1013570D02*
Y722030D01*
X1019247Y707447D01*
X1024924Y722030D01*
Y704530D01*
G01X1032380D02*
Y722030D01*
X1037620D01*
X1039367Y721155D01*
X1040677Y719113D01*
X1041114Y716780D01*
X1040677Y714447D01*
X1039585Y712697D01*
X1037620Y711821D01*
X1032380D01*
G01X1053155Y698697D02*
X1050972Y701613D01*
X1049880Y704530D01*
Y716196D01*
X1050972Y719113D01*
X1053155Y722030D01*
G01X1071747Y704530D02*
X1070000Y704822D01*
X1068472Y705988D01*
X1067162Y707738D01*
X1066288Y709780D01*
X1065852Y712113D01*
Y714447D01*
X1066288Y716780D01*
X1067162Y718822D01*
X1068472Y720571D01*
X1070000Y721738D01*
X1071747Y722030D01*
X1073493Y721738D01*
X1075022Y720571D01*
X1076332Y718822D01*
X1077206Y716780D01*
X1077642Y714447D01*
Y712113D01*
X1077206Y709780D01*
X1076332Y707738D01*
X1075022Y705988D01*
X1073493Y704822D01*
X1071747Y704530D01*
G01X1085535D02*
Y722030D01*
G01Y713572D02*
X1086627Y715030D01*
X1087719Y715905D01*
X1089465Y716196D01*
X1090775Y715905D01*
X1092304Y714738D01*
X1092959Y712988D01*
Y704530D01*
G01X1100197D02*
Y716196D01*
G01Y712988D02*
X1100852Y714447D01*
X1101944Y715613D01*
X1103472Y716196D01*
X1105000Y715613D01*
X1106092Y714447D01*
X1106747Y712988D01*
Y704530D01*
G01Y712988D02*
X1107402Y714447D01*
X1108493Y715613D01*
X1110022Y716196D01*
X1111550Y715613D01*
X1112642Y714447D01*
X1113297Y712697D01*
Y704530D01*
G01X1125339Y698697D02*
X1127522Y701613D01*
X1128614Y704530D01*
Y716196D01*
X1127522Y719113D01*
X1125339Y722030D01*
G01X977244Y739180D02*
Y756680D01*
X981610D01*
X983357Y755805D01*
X984667Y754638D01*
X985759Y752889D01*
X986632Y750846D01*
X986850Y747930D01*
X986632Y745013D01*
X985759Y742971D01*
X984667Y741221D01*
X983357Y740055D01*
X981610Y739180D01*
X977244D01*
G01X995180D02*
Y756680D01*
X1000420D01*
X1002167Y755805D01*
X1003477Y753763D01*
X1003914Y751430D01*
X1003477Y749097D01*
X1002385Y747347D01*
X1000420Y746471D01*
X995180D01*
G01X1031927Y756680D02*
X1037167D01*
G01X1034547D02*
Y739180D01*
G01X1031927D02*
X1037167D01*
G01X1046370D02*
Y756680D01*
X1052047Y742097D01*
X1057724Y756680D01*
Y739180D01*
G01X1065180D02*
Y756680D01*
X1070420D01*
X1072167Y755805D01*
X1073477Y753763D01*
X1073914Y751430D01*
X1073477Y749097D01*
X1072385Y747347D01*
X1070420Y746471D01*
X1065180D01*
G01X1091414Y739180D02*
X1082680D01*
Y756680D01*
X1091414D01*
G01X1087920Y748222D02*
X1082680D01*
G01X1099744Y739180D02*
Y756680D01*
X1104110D01*
X1105857Y755805D01*
X1107167Y754638D01*
X1108259Y752889D01*
X1109132Y750846D01*
X1109350Y747930D01*
X1109132Y745013D01*
X1108259Y742971D01*
X1107167Y741221D01*
X1105857Y740055D01*
X1104110Y739180D01*
X1099744D01*
G01X1116588D02*
X1122047Y756680D01*
X1127506Y739180D01*
G01X1125540Y745305D02*
X1118553D01*
G01X1134525Y739180D02*
Y756680D01*
X1144569Y739180D01*
Y756680D01*
G01X1161850Y755221D02*
X1160540Y756097D01*
X1159012Y756680D01*
X1157265D01*
X1155300Y755805D01*
X1153772Y754347D01*
X1152680Y752596D01*
X1151807Y749680D01*
X1151588Y747055D01*
X1152025Y744430D01*
X1152680Y742680D01*
X1153990Y740930D01*
X1155519Y739763D01*
X1157047Y739180D01*
X1158575D01*
X1160104Y739763D01*
X1161414Y740638D01*
X1162506Y741804D01*
G01X1178914Y739180D02*
X1170180D01*
Y756680D01*
X1178914D01*
G01X1175420Y748222D02*
X1170180D01*
G01X1209547Y756680D02*
Y739180D01*
G01X1204525Y756680D02*
X1214569D01*
G01X1221588Y739180D02*
X1227047Y756680D01*
X1232506Y739180D01*
G01X1230540Y745305D02*
X1223553D01*
G01X1246293Y748513D02*
X1247167Y749388D01*
X1247822Y750846D01*
X1248259Y752889D01*
X1247822Y754638D01*
X1246949Y755805D01*
X1245420Y756680D01*
X1239525D01*
Y739180D01*
X1246730D01*
X1248259Y740346D01*
X1249132Y742097D01*
X1249569Y744138D01*
X1249132Y746180D01*
X1247822Y747930D01*
X1246293Y748513D01*
X1239525D01*
G01X1257680Y756680D02*
Y739180D01*
X1266414D01*
G01X1283914D02*
X1275180D01*
Y756680D01*
X1283914D01*
G01X1280420Y748222D02*
X1275180D01*
G01X1297047Y738597D02*
X1296610Y738888D01*
Y739472D01*
X1297047Y739763D01*
X1297484Y739472D01*
Y738888D01*
X1297047Y738597D01*
G01Y746471D02*
X1296610Y746763D01*
Y747347D01*
X1297047Y747638D01*
X1297484Y747347D01*
Y746763D01*
X1297047Y746471D01*
G01X1327680Y756680D02*
Y739180D01*
X1336414D01*
G01X1349547D02*
X1351075Y739472D01*
X1352822Y740346D01*
X1353914Y741804D01*
X1354350Y743847D01*
X1353914Y745888D01*
X1352604Y747638D01*
X1350639Y748513D01*
X1348455D01*
X1347145Y749097D01*
X1346053Y750555D01*
X1345617Y752596D01*
X1346272Y754638D01*
X1347800Y756097D01*
X1349547Y756680D01*
X1351293Y756097D01*
X1352822Y754638D01*
X1353477Y752596D01*
X1353040Y750555D01*
X1351949Y749097D01*
X1350639Y748513D01*
X1348455D01*
X1346490Y747638D01*
X1345180Y745888D01*
X1344744Y743847D01*
X1345180Y741804D01*
X1346272Y740346D01*
X1348019Y739472D01*
X1349547Y739180D01*
G01X1027997Y565930D02*
Y583430D01*
X1025377Y579930D01*
G01Y565930D02*
X1030617D01*
G01X1045497Y583430D02*
X1043750Y582847D01*
X1042440Y581388D01*
X1041567Y579639D01*
X1040912Y577305D01*
X1040694Y574680D01*
X1040912Y572055D01*
X1041567Y569721D01*
X1042440Y567971D01*
X1043750Y566513D01*
X1045497Y565930D01*
X1047243Y566513D01*
X1048554Y567971D01*
X1049427Y569721D01*
X1050082Y572055D01*
X1050300Y574680D01*
X1050082Y577305D01*
X1049427Y579639D01*
X1048554Y581388D01*
X1047243Y582847D01*
X1045497Y583430D01*
G01X1062997D02*
X1061250Y582847D01*
X1059940Y581388D01*
X1059067Y579639D01*
X1058412Y577305D01*
X1058194Y574680D01*
X1058412Y572055D01*
X1059067Y569721D01*
X1059940Y567971D01*
X1061250Y566513D01*
X1062997Y565930D01*
X1064743Y566513D01*
X1066054Y567971D01*
X1066927Y569721D01*
X1067582Y572055D01*
X1067800Y574680D01*
X1067582Y577305D01*
X1066927Y579639D01*
X1066054Y581388D01*
X1064743Y582847D01*
X1062997Y583430D01*
G01X1080497Y565347D02*
X1080060Y565638D01*
Y566222D01*
X1080497Y566513D01*
X1080934Y566222D01*
Y565638D01*
X1080497Y565347D01*
G01X1097997Y583430D02*
X1096250Y582847D01*
X1094940Y581388D01*
X1094067Y579639D01*
X1093412Y577305D01*
X1093194Y574680D01*
X1093412Y572055D01*
X1094067Y569721D01*
X1094940Y567971D01*
X1096250Y566513D01*
X1097997Y565930D01*
X1099743Y566513D01*
X1101054Y567971D01*
X1101927Y569721D01*
X1102582Y572055D01*
X1102800Y574680D01*
X1102582Y577305D01*
X1101927Y579639D01*
X1101054Y581388D01*
X1099743Y582847D01*
X1097997Y583430D01*
G01X1023194Y634647D02*
X1032800Y647480D01*
G01X1027997Y649813D02*
Y632313D01*
G01X1032800Y634647D02*
X1023194Y647480D01*
G01X1021447Y641063D02*
X1034547D01*
G01X1041785Y637271D02*
X1043314Y635813D01*
X1045060Y635230D01*
X1046807Y635813D01*
X1048335Y637563D01*
X1049427Y640188D01*
X1049864Y642813D01*
Y646021D01*
X1049427Y648646D01*
X1048335Y650980D01*
X1047025Y652147D01*
X1045497Y652730D01*
X1043750Y652147D01*
X1042440Y650980D01*
X1041567Y649230D01*
X1041130Y646896D01*
X1041567Y644855D01*
X1042659Y642813D01*
X1043969Y641646D01*
X1045497Y641355D01*
X1047243Y641938D01*
X1048554Y643397D01*
X1049864Y646021D01*
G01X1058849Y649813D02*
X1060159Y651563D01*
X1061687Y652438D01*
X1063434Y652730D01*
X1065617Y652147D01*
X1067145Y650688D01*
X1067582Y648939D01*
X1067364Y647188D01*
X1066490Y645730D01*
X1062124Y642813D01*
X1060159Y640772D01*
X1058849Y637854D01*
X1058412Y635230D01*
X1067582D01*
G01X1080497Y634647D02*
X1080060Y634938D01*
Y635522D01*
X1080497Y635813D01*
X1080934Y635522D01*
Y634938D01*
X1080497Y634647D01*
G01X1097997Y652730D02*
X1096250Y652147D01*
X1094940Y650688D01*
X1094067Y648939D01*
X1093412Y646605D01*
X1093194Y643980D01*
X1093412Y641355D01*
X1094067Y639021D01*
X1094940Y637271D01*
X1096250Y635813D01*
X1097997Y635230D01*
X1099743Y635813D01*
X1101054Y637271D01*
X1101927Y639021D01*
X1102582Y641355D01*
X1102800Y643980D01*
X1102582Y646605D01*
X1101927Y648939D01*
X1101054Y650688D01*
X1099743Y652147D01*
X1097997Y652730D01*
G01X1023194Y599997D02*
X1032800Y612830D01*
G01X1027997Y615163D02*
Y597663D01*
G01X1032800Y599997D02*
X1023194Y612830D01*
G01X1021447Y606413D02*
X1034547D01*
G01X1041785Y602621D02*
X1043314Y601163D01*
X1045060Y600580D01*
X1046807Y601163D01*
X1048335Y602913D01*
X1049427Y605538D01*
X1049864Y608163D01*
Y611371D01*
X1049427Y613996D01*
X1048335Y616330D01*
X1047025Y617497D01*
X1045497Y618080D01*
X1043750Y617497D01*
X1042440Y616330D01*
X1041567Y614580D01*
X1041130Y612246D01*
X1041567Y610205D01*
X1042659Y608163D01*
X1043969Y606996D01*
X1045497Y606705D01*
X1047243Y607288D01*
X1048554Y608747D01*
X1049864Y611371D01*
G01X1062560Y600580D02*
X1062997Y604371D01*
X1063652Y607580D01*
X1064525Y610497D01*
X1065617Y613705D01*
X1067364Y618080D01*
X1058630D01*
G01X1080497Y599997D02*
X1080060Y600288D01*
Y600872D01*
X1080497Y601163D01*
X1080934Y600872D01*
Y600288D01*
X1080497Y599997D01*
G01X1097997Y618080D02*
X1096250Y617497D01*
X1094940Y616038D01*
X1094067Y614289D01*
X1093412Y611955D01*
X1093194Y609330D01*
X1093412Y606705D01*
X1094067Y604371D01*
X1094940Y602621D01*
X1096250Y601163D01*
X1097997Y600580D01*
X1099743Y601163D01*
X1101054Y602621D01*
X1101927Y604371D01*
X1102582Y606705D01*
X1102800Y609330D01*
X1102582Y611955D01*
X1101927Y614289D01*
X1101054Y616038D01*
X1099743Y617497D01*
X1097997Y618080D01*
G01X1036747Y669880D02*
X1038275Y670172D01*
X1040022Y671046D01*
X1041114Y672504D01*
X1041550Y674547D01*
X1041114Y676588D01*
X1039804Y678338D01*
X1037839Y679213D01*
X1035655D01*
X1034345Y679797D01*
X1033253Y681255D01*
X1032817Y683296D01*
X1033472Y685338D01*
X1035000Y686797D01*
X1036747Y687380D01*
X1038493Y686797D01*
X1040022Y685338D01*
X1040677Y683296D01*
X1040240Y681255D01*
X1039149Y679797D01*
X1037839Y679213D01*
X1035655D01*
X1033690Y678338D01*
X1032380Y676588D01*
X1031944Y674547D01*
X1032380Y672504D01*
X1033472Y671046D01*
X1035219Y670172D01*
X1036747Y669880D01*
G01X1049444Y672504D02*
X1050753Y671046D01*
X1052282Y670172D01*
X1054247Y669880D01*
X1056212Y670463D01*
X1057740Y671630D01*
X1058832Y673671D01*
X1059050Y676005D01*
X1058614Y678338D01*
X1057522Y679797D01*
X1055993Y680963D01*
X1054465Y681255D01*
X1052937Y680963D01*
X1050972Y679797D01*
X1051627Y687380D01*
X1057522D01*
G01X1071747Y669297D02*
X1071310Y669588D01*
Y670172D01*
X1071747Y670463D01*
X1072184Y670172D01*
Y669588D01*
X1071747Y669297D01*
G01X1089247Y687380D02*
X1087500Y686797D01*
X1086190Y685338D01*
X1085317Y683589D01*
X1084662Y681255D01*
X1084444Y678630D01*
X1084662Y676005D01*
X1085317Y673671D01*
X1086190Y671921D01*
X1087500Y670463D01*
X1089247Y669880D01*
X1090993Y670463D01*
X1092304Y671921D01*
X1093177Y673671D01*
X1093832Y676005D01*
X1094050Y678630D01*
X1093832Y681255D01*
X1093177Y683589D01*
X1092304Y685338D01*
X1090993Y686797D01*
X1089247Y687380D01*
G01X1187697Y722030D02*
X1190753Y704530D01*
X1194247Y722030D01*
X1197740Y704530D01*
X1200797Y722030D01*
G01X1209127D02*
X1214367D01*
G01X1211747D02*
Y704530D01*
G01X1209127D02*
X1214367D01*
G01X1224444D02*
Y722030D01*
X1228810D01*
X1230557Y721155D01*
X1231867Y719988D01*
X1232959Y718239D01*
X1233832Y716196D01*
X1234050Y713280D01*
X1233832Y710363D01*
X1232959Y708321D01*
X1231867Y706571D01*
X1230557Y705405D01*
X1228810Y704530D01*
X1224444D01*
G01X1246747Y722030D02*
Y704530D01*
G01X1241725Y722030D02*
X1251769D01*
G01X1259662Y704530D02*
Y722030D01*
G01X1268832D02*
Y704530D01*
G01Y713280D02*
X1259662D01*
G01X1280655Y698697D02*
X1278472Y701613D01*
X1277380Y704530D01*
Y716196D01*
X1278472Y719113D01*
X1280655Y722030D01*
G01X1292697Y704530D02*
Y716196D01*
G01Y712988D02*
X1293352Y714447D01*
X1294444Y715613D01*
X1295972Y716196D01*
X1297500Y715613D01*
X1298592Y714447D01*
X1299247Y712988D01*
Y704530D01*
G01Y712988D02*
X1299902Y714447D01*
X1300993Y715613D01*
X1302522Y716196D01*
X1304050Y715613D01*
X1305142Y714447D01*
X1305797Y712697D01*
Y704530D01*
G01X1316747Y716196D02*
Y704530D01*
G01Y720863D02*
X1316310Y721155D01*
Y721738D01*
X1316747Y722030D01*
X1317184Y721738D01*
Y721155D01*
X1316747Y720863D01*
G01X1334247Y704530D02*
Y722030D01*
G01X1348472Y706571D02*
X1349564Y705405D01*
X1351092Y704530D01*
X1352402D01*
X1353712Y705113D01*
X1354585Y705988D01*
X1355022Y707154D01*
X1354804Y708905D01*
X1353930Y709780D01*
X1350000Y711530D01*
X1349127Y713572D01*
X1349564Y715030D01*
X1350437Y715905D01*
X1351747Y716196D01*
X1353057Y715905D01*
X1354367Y715030D01*
G01X1370339Y698697D02*
X1372522Y701613D01*
X1373614Y704530D01*
Y716196D01*
X1372522Y719113D01*
X1370339Y722030D01*
G01X1223117Y565930D02*
Y583430D01*
X1215038Y570888D01*
X1225956D01*
G01X1237997Y565347D02*
X1237560Y565638D01*
Y566222D01*
X1237997Y566513D01*
X1238434Y566222D01*
Y565638D01*
X1237997Y565347D01*
G01X1251785Y567971D02*
X1253314Y566513D01*
X1255060Y565930D01*
X1256807Y566513D01*
X1258335Y568263D01*
X1259427Y570888D01*
X1259864Y573513D01*
Y576721D01*
X1259427Y579346D01*
X1258335Y581680D01*
X1257025Y582847D01*
X1255497Y583430D01*
X1253750Y582847D01*
X1252440Y581680D01*
X1251567Y579930D01*
X1251130Y577596D01*
X1251567Y575555D01*
X1252659Y573513D01*
X1253969Y572346D01*
X1255497Y572055D01*
X1257243Y572638D01*
X1258554Y574097D01*
X1259864Y576721D01*
G01X1269067Y565347D02*
X1276927Y583430D01*
G01X1290497Y565930D02*
Y583430D01*
X1287877Y579930D01*
G01Y565930D02*
X1293117D01*
G01X1307997D02*
Y583430D01*
X1305377Y579930D01*
G01Y565930D02*
X1310617D01*
G01X1325497Y565347D02*
X1325060Y565638D01*
Y566222D01*
X1325497Y566513D01*
X1325934Y566222D01*
Y565638D01*
X1325497Y565347D01*
G01X1342997Y565930D02*
Y583430D01*
X1340377Y579930D01*
G01Y565930D02*
X1345617D01*
G01X1215694Y638730D02*
X1217003Y636688D01*
X1218750Y635522D01*
X1220715Y635230D01*
X1222462Y635522D01*
X1224209Y636980D01*
X1225300Y638730D01*
X1225519Y640480D01*
X1225082Y642521D01*
X1223554Y643980D01*
X1222025Y644563D01*
X1220060D01*
G01X1222025D02*
X1223335Y645438D01*
X1224427Y646896D01*
X1224864Y648646D01*
X1224427Y650397D01*
X1223335Y651855D01*
X1221370Y652730D01*
X1219405Y652438D01*
X1217440Y651271D01*
G01X1237997Y634647D02*
X1237560Y634938D01*
Y635522D01*
X1237997Y635813D01*
X1238434Y635522D01*
Y634938D01*
X1237997Y634647D01*
G01X1255060Y635230D02*
X1255497Y639021D01*
X1256152Y642230D01*
X1257025Y645147D01*
X1258117Y648355D01*
X1259864Y652730D01*
X1251130D01*
G01X1268194Y637854D02*
X1269503Y636396D01*
X1271032Y635522D01*
X1272997Y635230D01*
X1274962Y635813D01*
X1276490Y636980D01*
X1277582Y639021D01*
X1277800Y641355D01*
X1277364Y643688D01*
X1276272Y645147D01*
X1274743Y646313D01*
X1273215Y646605D01*
X1271687Y646313D01*
X1269722Y645147D01*
X1270377Y652730D01*
X1276272D01*
G01X1286567Y634647D02*
X1294427Y652730D01*
G01X1303194Y638730D02*
X1304503Y636688D01*
X1306250Y635522D01*
X1308215Y635230D01*
X1309962Y635522D01*
X1311709Y636980D01*
X1312800Y638730D01*
X1313019Y640480D01*
X1312582Y642521D01*
X1311054Y643980D01*
X1309525Y644563D01*
X1307560D01*
G01X1309525D02*
X1310835Y645438D01*
X1311927Y646896D01*
X1312364Y648646D01*
X1311927Y650397D01*
X1310835Y651855D01*
X1308870Y652730D01*
X1306905Y652438D01*
X1304940Y651271D01*
G01X1325497Y634647D02*
X1325060Y634938D01*
Y635522D01*
X1325497Y635813D01*
X1325934Y635522D01*
Y634938D01*
X1325497Y634647D01*
G01X1338194Y637854D02*
X1339503Y636396D01*
X1341032Y635522D01*
X1342997Y635230D01*
X1344962Y635813D01*
X1346490Y636980D01*
X1347582Y639021D01*
X1347800Y641355D01*
X1347364Y643688D01*
X1346272Y645147D01*
X1344743Y646313D01*
X1343215Y646605D01*
X1341687Y646313D01*
X1339722Y645147D01*
X1340377Y652730D01*
X1346272D01*
G01X1224444Y604080D02*
X1225753Y602038D01*
X1227500Y600872D01*
X1229465Y600580D01*
X1231212Y600872D01*
X1232959Y602330D01*
X1234050Y604080D01*
X1234269Y605830D01*
X1233832Y607871D01*
X1232304Y609330D01*
X1230775Y609913D01*
X1228810D01*
G01X1230775D02*
X1232085Y610788D01*
X1233177Y612246D01*
X1233614Y613996D01*
X1233177Y615747D01*
X1232085Y617205D01*
X1230120Y618080D01*
X1228155Y617788D01*
X1226190Y616621D01*
G01X1246747Y599997D02*
X1246310Y600288D01*
Y600872D01*
X1246747Y601163D01*
X1247184Y600872D01*
Y600288D01*
X1246747Y599997D01*
G01X1259444Y603204D02*
X1260753Y601746D01*
X1262282Y600872D01*
X1264247Y600580D01*
X1266212Y601163D01*
X1267740Y602330D01*
X1268832Y604371D01*
X1269050Y606705D01*
X1268614Y609038D01*
X1267522Y610497D01*
X1265993Y611663D01*
X1264465Y611955D01*
X1262937Y611663D01*
X1260972Y610497D01*
X1261627Y618080D01*
X1267522D01*
G01X1277817Y599997D02*
X1285677Y618080D01*
G01X1301867Y600580D02*
Y618080D01*
X1293788Y605538D01*
X1304706D01*
G01X1316747Y599997D02*
X1316310Y600288D01*
Y600872D01*
X1316747Y601163D01*
X1317184Y600872D01*
Y600288D01*
X1316747Y599997D01*
G01X1334247Y618080D02*
X1332500Y617497D01*
X1331190Y616038D01*
X1330317Y614289D01*
X1329662Y611955D01*
X1329444Y609330D01*
X1329662Y606705D01*
X1330317Y604371D01*
X1331190Y602621D01*
X1332500Y601163D01*
X1334247Y600580D01*
X1335993Y601163D01*
X1337304Y602621D01*
X1338177Y604371D01*
X1338832Y606705D01*
X1339050Y609330D01*
X1338832Y611955D01*
X1338177Y614289D01*
X1337304Y616038D01*
X1335993Y617497D01*
X1334247Y618080D01*
G01X1215694Y672504D02*
X1217003Y671046D01*
X1218532Y670172D01*
X1220497Y669880D01*
X1222462Y670463D01*
X1223990Y671630D01*
X1225082Y673671D01*
X1225300Y676005D01*
X1224864Y678338D01*
X1223772Y679797D01*
X1222243Y680963D01*
X1220715Y681255D01*
X1219187Y680963D01*
X1217222Y679797D01*
X1217877Y687380D01*
X1223772D01*
G01X1237997Y669297D02*
X1237560Y669588D01*
Y670172D01*
X1237997Y670463D01*
X1238434Y670172D01*
Y669588D01*
X1237997Y669297D01*
G01X1255060Y669880D02*
X1255497Y673671D01*
X1256152Y676880D01*
X1257025Y679797D01*
X1258117Y683005D01*
X1259864Y687380D01*
X1251130D01*
G01X1268194Y672504D02*
X1269503Y671046D01*
X1271032Y670172D01*
X1272997Y669880D01*
X1274962Y670463D01*
X1276490Y671630D01*
X1277582Y673671D01*
X1277800Y676005D01*
X1277364Y678338D01*
X1276272Y679797D01*
X1274743Y680963D01*
X1273215Y681255D01*
X1271687Y680963D01*
X1269722Y679797D01*
X1270377Y687380D01*
X1276272D01*
G01X1286567Y669297D02*
X1294427Y687380D01*
G01X1303849Y677171D02*
X1305377Y679213D01*
X1306687Y680380D01*
X1308434Y680963D01*
X1309962Y680380D01*
X1311054Y679213D01*
X1311927Y677463D01*
X1312145Y675422D01*
X1311927Y673671D01*
X1311054Y671921D01*
X1309743Y670463D01*
X1308215Y669880D01*
X1306469Y670463D01*
X1304940Y672213D01*
X1304067Y674838D01*
X1303849Y677755D01*
X1304285Y681546D01*
X1304940Y683589D01*
X1306032Y685630D01*
X1307560Y687088D01*
X1309089Y687380D01*
X1310617Y686797D01*
X1311709Y685338D01*
G01X1325497Y669297D02*
X1325060Y669588D01*
Y670172D01*
X1325497Y670463D01*
X1325934Y670172D01*
Y669588D01*
X1325497Y669297D01*
G01X1338194Y672504D02*
X1339503Y671046D01*
X1341032Y670172D01*
X1342997Y669880D01*
X1344962Y670463D01*
X1346490Y671630D01*
X1347582Y673671D01*
X1347800Y676005D01*
X1347364Y678338D01*
X1346272Y679797D01*
X1344743Y680963D01*
X1343215Y681255D01*
X1341687Y680963D01*
X1339722Y679797D01*
X1340377Y687380D01*
X1346272D01*
G01X1451944Y565930D02*
Y583430D01*
X1456310D01*
X1458057Y582555D01*
X1459367Y581388D01*
X1460459Y579639D01*
X1461332Y577596D01*
X1461550Y574680D01*
X1461332Y571763D01*
X1460459Y569721D01*
X1459367Y567971D01*
X1458057Y566805D01*
X1456310Y565930D01*
X1451944D01*
G01X1469880D02*
Y583430D01*
X1475120D01*
X1476867Y582555D01*
X1478177Y580513D01*
X1478614Y578180D01*
X1478177Y575847D01*
X1477085Y574097D01*
X1475120Y573221D01*
X1469880D01*
G01X1451944Y635230D02*
Y652730D01*
X1456310D01*
X1458057Y651855D01*
X1459367Y650688D01*
X1460459Y648939D01*
X1461332Y646896D01*
X1461550Y643980D01*
X1461332Y641063D01*
X1460459Y639021D01*
X1459367Y637271D01*
X1458057Y636105D01*
X1456310Y635230D01*
X1451944D01*
G01X1469880D02*
Y652730D01*
X1475120D01*
X1476867Y651855D01*
X1478177Y649813D01*
X1478614Y647480D01*
X1478177Y645147D01*
X1477085Y643397D01*
X1475120Y642521D01*
X1469880D01*
G01X1451944Y600580D02*
Y618080D01*
X1456310D01*
X1458057Y617205D01*
X1459367Y616038D01*
X1460459Y614289D01*
X1461332Y612246D01*
X1461550Y609330D01*
X1461332Y606413D01*
X1460459Y604371D01*
X1459367Y602621D01*
X1458057Y601455D01*
X1456310Y600580D01*
X1451944D01*
G01X1469880D02*
Y618080D01*
X1475120D01*
X1476867Y617205D01*
X1478177Y615163D01*
X1478614Y612830D01*
X1478177Y610497D01*
X1477085Y608747D01*
X1475120Y607871D01*
X1469880D01*
G01X1439247Y722030D02*
Y704530D01*
G01X1434225Y722030D02*
X1444269D01*
G01X1456747Y704530D02*
Y712405D01*
X1452380Y722030D01*
G01X1461114D02*
X1456747Y712405D01*
G01X1469880Y704530D02*
Y722030D01*
X1475120D01*
X1476867Y721155D01*
X1478177Y719113D01*
X1478614Y716780D01*
X1478177Y714447D01*
X1477085Y712697D01*
X1475120Y711821D01*
X1469880D01*
G01X1496114Y704530D02*
X1487380D01*
Y722030D01*
X1496114D01*
G01X1492620Y713572D02*
X1487380D01*
G01X1451944Y669880D02*
Y687380D01*
X1456310D01*
X1458057Y686505D01*
X1459367Y685338D01*
X1460459Y683589D01*
X1461332Y681546D01*
X1461550Y678630D01*
X1461332Y675713D01*
X1460459Y673671D01*
X1459367Y671921D01*
X1458057Y670755D01*
X1456310Y669880D01*
X1451944D01*
G01X1469880D02*
Y687380D01*
X1475120D01*
X1476867Y686505D01*
X1478177Y684463D01*
X1478614Y682130D01*
X1478177Y679797D01*
X1477085Y678047D01*
X1475120Y677171D01*
X1469880D01*
G01X1539880Y704530D02*
Y722030D01*
X1545339D01*
X1547085Y721155D01*
X1548177Y719988D01*
X1548614Y717655D01*
X1548177Y715321D01*
X1546867Y713863D01*
X1545339Y712988D01*
X1539880D01*
G01X1545339D02*
X1548614Y704530D01*
G01X1558472Y712405D02*
X1565459D01*
X1564804Y714447D01*
X1563712Y715613D01*
X1562184Y716196D01*
X1560655Y715905D01*
X1559345Y715030D01*
X1558472Y712988D01*
X1558035Y711238D01*
Y709488D01*
X1558472Y707738D01*
X1559564Y705988D01*
X1560874Y704822D01*
X1562402Y704530D01*
X1563930Y705113D01*
X1565459Y706863D01*
G01X1577937Y704530D02*
Y719405D01*
X1578374Y720863D01*
X1579247Y721738D01*
X1580557Y722030D01*
X1581867Y721447D01*
X1582522Y719988D01*
G01X1579902Y715030D02*
X1575535D01*
G01X1596747Y703947D02*
X1596310Y704238D01*
Y704822D01*
X1596747Y705113D01*
X1597184Y704822D01*
Y704238D01*
X1596747Y703947D01*
G01X1627380Y704530D02*
Y722030D01*
X1632620D01*
X1634367Y721155D01*
X1635677Y719113D01*
X1636114Y716780D01*
X1635677Y714447D01*
X1634585Y712697D01*
X1632620Y711821D01*
X1627380D01*
G01X1649247Y704530D02*
Y722030D01*
G01X1670677Y704530D02*
Y716196D01*
G01Y714155D02*
X1669804Y715321D01*
X1668493Y715905D01*
X1666965Y716196D01*
X1665437Y715613D01*
X1664127Y714447D01*
X1663253Y712697D01*
X1662817Y710363D01*
X1663253Y708030D01*
X1664127Y706280D01*
X1665437Y705113D01*
X1666965Y704530D01*
X1668493Y704822D01*
X1669804Y705696D01*
X1670677Y706863D01*
G01X1680535Y704530D02*
Y716196D01*
G01Y713280D02*
X1681409Y714738D01*
X1682719Y715905D01*
X1684465Y716196D01*
X1685993Y715905D01*
X1687304Y714738D01*
X1687959Y712697D01*
Y704530D01*
G01X1698472Y712405D02*
X1705459D01*
X1704804Y714447D01*
X1703712Y715613D01*
X1702184Y716196D01*
X1700655Y715905D01*
X1699345Y715030D01*
X1698472Y712988D01*
X1698035Y711238D01*
Y709488D01*
X1698472Y707738D01*
X1699564Y705988D01*
X1700874Y704822D01*
X1702402Y704530D01*
X1703930Y705113D01*
X1705459Y706863D01*
G01X1609880Y583430D02*
Y565930D01*
X1618614D01*
G01X1631310D02*
X1631747Y569721D01*
X1632402Y572930D01*
X1633275Y575847D01*
X1634367Y579055D01*
X1636114Y583430D01*
X1627380D01*
G01X1609880Y652730D02*
Y635230D01*
X1618614D01*
G01X1631310D02*
X1631747Y639021D01*
X1632402Y642230D01*
X1633275Y645147D01*
X1634367Y648355D01*
X1636114Y652730D01*
X1627380D01*
G01X1609880Y618080D02*
Y600580D01*
X1618614D01*
G01X1631310D02*
X1631747Y604371D01*
X1632402Y607580D01*
X1633275Y610497D01*
X1634367Y613705D01*
X1636114Y618080D01*
X1627380D01*
G01X1609880Y687380D02*
Y669880D01*
X1618614D01*
G01X1631310D02*
X1631747Y673671D01*
X1632402Y676880D01*
X1633275Y679797D01*
X1634367Y683005D01*
X1636114Y687380D01*
X1627380D01*
G01X1744744Y703947D02*
X1754350Y716780D01*
G01X1749547Y719113D02*
Y701613D01*
G01X1754350Y703947D02*
X1744744Y716780D01*
G01X1742997Y710363D02*
X1756097D01*
G01X1781709D02*
X1787385D01*
G01X1814744Y704530D02*
Y722030D01*
X1819110D01*
X1820857Y721155D01*
X1822167Y719988D01*
X1823259Y718239D01*
X1824132Y716196D01*
X1824350Y713280D01*
X1824132Y710363D01*
X1823259Y708321D01*
X1822167Y706571D01*
X1820857Y705405D01*
X1819110Y704530D01*
X1814744D01*
G01X1833772Y712405D02*
X1840759D01*
X1840104Y714447D01*
X1839012Y715613D01*
X1837484Y716196D01*
X1835955Y715905D01*
X1834645Y715030D01*
X1833772Y712988D01*
X1833335Y711238D01*
Y709488D01*
X1833772Y707738D01*
X1834864Y705988D01*
X1836174Y704822D01*
X1837702Y704530D01*
X1839230Y705113D01*
X1840759Y706863D01*
G01X1850835Y704530D02*
Y716196D01*
G01Y713280D02*
X1851709Y714738D01*
X1853019Y715905D01*
X1854765Y716196D01*
X1856293Y715905D01*
X1857604Y714738D01*
X1858259Y712697D01*
Y704530D01*
G01X1872047D02*
X1870737Y704822D01*
X1869427Y705988D01*
X1868553Y708030D01*
X1868117Y710363D01*
X1868553Y712697D01*
X1869427Y714738D01*
X1870737Y715905D01*
X1872047Y716196D01*
X1873357Y715905D01*
X1874667Y714738D01*
X1875540Y712697D01*
X1875759Y710363D01*
X1875540Y708030D01*
X1874667Y705988D01*
X1873357Y704822D01*
X1872047Y704530D01*
G01X1889547Y722030D02*
Y704530D01*
G01X1886490Y716196D02*
X1892604D01*
G01X1903772Y712405D02*
X1910759D01*
X1910104Y714447D01*
X1909012Y715613D01*
X1907484Y716196D01*
X1905955Y715905D01*
X1904645Y715030D01*
X1903772Y712988D01*
X1903335Y711238D01*
Y709488D01*
X1903772Y707738D01*
X1904864Y705988D01*
X1906174Y704822D01*
X1907702Y704530D01*
X1909230Y705113D01*
X1910759Y706863D01*
G01X1921272Y706571D02*
X1922364Y705405D01*
X1923892Y704530D01*
X1925202D01*
X1926512Y705113D01*
X1927385Y705988D01*
X1927822Y707154D01*
X1927604Y708905D01*
X1926730Y709780D01*
X1922800Y711530D01*
X1921927Y713572D01*
X1922364Y715030D01*
X1923237Y715905D01*
X1924547Y716196D01*
X1925857Y715905D01*
X1927167Y715030D01*
G01X1959547Y722030D02*
Y704530D01*
G01X1956490Y716196D02*
X1962604D01*
G01X1973335Y704530D02*
Y722030D01*
G01Y713572D02*
X1974427Y715030D01*
X1975519Y715905D01*
X1977265Y716196D01*
X1978575Y715905D01*
X1980104Y714738D01*
X1980759Y712988D01*
Y704530D01*
G01X1998477D02*
Y716196D01*
G01Y714155D02*
X1997604Y715321D01*
X1996293Y715905D01*
X1994765Y716196D01*
X1993237Y715613D01*
X1991927Y714447D01*
X1991053Y712697D01*
X1990617Y710363D01*
X1991053Y708030D01*
X1991927Y706280D01*
X1993237Y705113D01*
X1994765Y704530D01*
X1996293Y704822D01*
X1997604Y705696D01*
X1998477Y706863D01*
G01X2012047Y722030D02*
Y704530D01*
G01X2008990Y716196D02*
X2015104D01*
G01X2047047Y722030D02*
Y704530D01*
G01X2043990Y716196D02*
X2050104D01*
G01X2060835Y704530D02*
Y722030D01*
G01Y713572D02*
X2061927Y715030D01*
X2063019Y715905D01*
X2064765Y716196D01*
X2066075Y715905D01*
X2067604Y714738D01*
X2068259Y712988D01*
Y704530D01*
G01X2082047Y716196D02*
Y704530D01*
G01Y720863D02*
X2081610Y721155D01*
Y721738D01*
X2082047Y722030D01*
X2082484Y721738D01*
Y721155D01*
X2082047Y720863D01*
G01X2096272Y706571D02*
X2097364Y705405D01*
X2098892Y704530D01*
X2100202D01*
X2101512Y705113D01*
X2102385Y705988D01*
X2102822Y707154D01*
X2102604Y708905D01*
X2101730Y709780D01*
X2097800Y711530D01*
X2096927Y713572D01*
X2097364Y715030D01*
X2098237Y715905D01*
X2099547Y716196D01*
X2100857Y715905D01*
X2102167Y715030D01*
G01X2131927Y722030D02*
X2137167D01*
G01X2134547D02*
Y704530D01*
G01X2131927D02*
X2137167D01*
G01X2145497D02*
Y716196D01*
G01Y712988D02*
X2146152Y714447D01*
X2147244Y715613D01*
X2148772Y716196D01*
X2150300Y715613D01*
X2151392Y714447D01*
X2152047Y712988D01*
Y704530D01*
G01Y712988D02*
X2152702Y714447D01*
X2153793Y715613D01*
X2155322Y716196D01*
X2156850Y715613D01*
X2157942Y714447D01*
X2158597Y712697D01*
Y704530D01*
G01X2165617Y698697D02*
Y716196D01*
G01Y713572D02*
X2166709Y715030D01*
X2167800Y715905D01*
X2169547Y716196D01*
X2171075Y715905D01*
X2172604Y714447D01*
X2173259Y712405D01*
X2173477Y710363D01*
X2173259Y708321D01*
X2172604Y706280D01*
X2171293Y705113D01*
X2169547Y704530D01*
X2168019Y704822D01*
X2166490Y705696D01*
X2165617Y706863D01*
G01X2183772Y712405D02*
X2190759D01*
X2190104Y714447D01*
X2189012Y715613D01*
X2187484Y716196D01*
X2185955Y715905D01*
X2184645Y715030D01*
X2183772Y712988D01*
X2183335Y711238D01*
Y709488D01*
X2183772Y707738D01*
X2184864Y705988D01*
X2186174Y704822D01*
X2187702Y704530D01*
X2189230Y705113D01*
X2190759Y706863D01*
G01X2208477Y722030D02*
Y704530D01*
G01Y707154D02*
X2207604Y705696D01*
X2206293Y704822D01*
X2204765Y704530D01*
X2203019Y705113D01*
X2201709Y706571D01*
X2200835Y708321D01*
X2200617Y710363D01*
X2200835Y712405D01*
X2201709Y714155D01*
X2203019Y715613D01*
X2204765Y716196D01*
X2206293Y715905D01*
X2207385Y715321D01*
X2208477Y714155D01*
G01X2225977Y704530D02*
Y716196D01*
G01Y714155D02*
X2225104Y715321D01*
X2223793Y715905D01*
X2222265Y716196D01*
X2220737Y715613D01*
X2219427Y714447D01*
X2218553Y712697D01*
X2218117Y710363D01*
X2218553Y708030D01*
X2219427Y706280D01*
X2220737Y705113D01*
X2222265Y704530D01*
X2223793Y704822D01*
X2225104Y705696D01*
X2225977Y706863D01*
G01X2235835Y704530D02*
Y716196D01*
G01Y713280D02*
X2236709Y714738D01*
X2238019Y715905D01*
X2239765Y716196D01*
X2241293Y715905D01*
X2242604Y714738D01*
X2243259Y712697D01*
Y704530D01*
G01X2260540Y714738D02*
X2259012Y715905D01*
X2257702Y716196D01*
X2255955Y715613D01*
X2254645Y714447D01*
X2253772Y712405D01*
X2253553Y710363D01*
X2253772Y708321D01*
X2254645Y706571D01*
X2255955Y705113D01*
X2257702Y704530D01*
X2259230Y705113D01*
X2260540Y706280D01*
G01X2271272Y712405D02*
X2278259D01*
X2277604Y714447D01*
X2276512Y715613D01*
X2274984Y716196D01*
X2273455Y715905D01*
X2272145Y715030D01*
X2271272Y712988D01*
X2270835Y711238D01*
Y709488D01*
X2271272Y707738D01*
X2272364Y705988D01*
X2273674Y704822D01*
X2275202Y704530D01*
X2276730Y705113D01*
X2278259Y706863D01*
G01X1819547Y681546D02*
Y669880D01*
G01Y686213D02*
X1819110Y686505D01*
Y687088D01*
X1819547Y687380D01*
X1819984Y687088D01*
Y686505D01*
X1819547Y686213D01*
G01X1833772Y671921D02*
X1834864Y670755D01*
X1836392Y669880D01*
X1837702D01*
X1839012Y670463D01*
X1839885Y671338D01*
X1840322Y672504D01*
X1840104Y674255D01*
X1839230Y675130D01*
X1835300Y676880D01*
X1834427Y678922D01*
X1834864Y680380D01*
X1835737Y681255D01*
X1837047Y681546D01*
X1838357Y681255D01*
X1839667Y680380D01*
G01X1867025Y669880D02*
Y687380D01*
X1877069Y669880D01*
Y687380D01*
G01X1889547Y669880D02*
X1887800Y670172D01*
X1886272Y671338D01*
X1884962Y673088D01*
X1884088Y675130D01*
X1883652Y677463D01*
Y679797D01*
X1884088Y682130D01*
X1884962Y684172D01*
X1886272Y685921D01*
X1887800Y687088D01*
X1889547Y687380D01*
X1891293Y687088D01*
X1892822Y685921D01*
X1894132Y684172D01*
X1895006Y682130D01*
X1895442Y679797D01*
Y677463D01*
X1895006Y675130D01*
X1894132Y673088D01*
X1892822Y671338D01*
X1891293Y670172D01*
X1889547Y669880D01*
G01X1907047Y687380D02*
Y669880D01*
G01X1902025Y687380D02*
X1912069D01*
G01X1938335Y681546D02*
Y673380D01*
X1939209Y671338D01*
X1940519Y670172D01*
X1942047Y669880D01*
X1943575Y670172D01*
X1944885Y671338D01*
X1945759Y673380D01*
G01Y669880D02*
Y681546D01*
G01X1956272Y671921D02*
X1957364Y670755D01*
X1958892Y669880D01*
X1960202D01*
X1961512Y670463D01*
X1962385Y671338D01*
X1962822Y672504D01*
X1962604Y674255D01*
X1961730Y675130D01*
X1957800Y676880D01*
X1956927Y678922D01*
X1957364Y680380D01*
X1958237Y681255D01*
X1959547Y681546D01*
X1960857Y681255D01*
X1962167Y680380D01*
G01X1973772Y677755D02*
X1980759D01*
X1980104Y679797D01*
X1979012Y680963D01*
X1977484Y681546D01*
X1975955Y681255D01*
X1974645Y680380D01*
X1973772Y678338D01*
X1973335Y676588D01*
Y674838D01*
X1973772Y673088D01*
X1974864Y671338D01*
X1976174Y670172D01*
X1977702Y669880D01*
X1979230Y670463D01*
X1980759Y672213D01*
G01X1998477Y687380D02*
Y669880D01*
G01Y672504D02*
X1997604Y671046D01*
X1996293Y670172D01*
X1994765Y669880D01*
X1993019Y670463D01*
X1991709Y671921D01*
X1990835Y673671D01*
X1990617Y675713D01*
X1990835Y677755D01*
X1991709Y679505D01*
X1993019Y680963D01*
X1994765Y681546D01*
X1996293Y681255D01*
X1997385Y680671D01*
X1998477Y679505D01*
G01X3937Y0D02*
X116260D01*
G01X0Y3937D02*
G03X3937Y0I3937J0D01*
G01X0Y723480D02*
Y3937D01*
G01X416Y725241D02*
G03X0Y723480I3521J-1761D01*
G01X18597Y761603D02*
X416Y725241D01*
G01X77756Y98425D02*
G03X63976I-6890J0D01*
G01D02*
G03X77756I6890J0D01*
G01X83071Y245079D02*
G03Y231693I0J-6693D01*
G01X77756Y472441D02*
G03X63976I-6890J0D01*
G01D02*
G03X77756I6890J0D01*
G01X57087Y740157D02*
G03X41339I-7874J0D01*
G01D02*
G03X57087I7874J0D01*
G01X22118Y763780D02*
G03X18597Y761603I1J-3937D01*
G01X386149Y763780D02*
X22118D01*
G01X128071Y3937D02*
G03X132008Y0I3937J0D01*
G01X116260D02*
G03X120197Y3937I0J3937D01*
G01X132008Y0D02*
X275709D01*
G01X120197Y3937D02*
Y429331D01*
G01X128071Y59055D02*
Y3937D01*
G01Y59055D02*
G03X120197I-3937J0D01*
G01X128071D02*
G03X120197I-3937J0D01*
G01X128071Y98425D02*
Y421457D01*
G01X120197Y98425D02*
G03X128071I3937J0D01*
G01X120197D02*
G03X128071I3937J0D01*
G01X96457Y231693D02*
G03Y245079I0J6693D01*
G01X83071D02*
X96457D01*
G01Y231693D02*
X83071D01*
G01X96654Y413583D02*
G03X83661I-6496J0D01*
G01D02*
G03X96654I6496J0D01*
G01X132008Y425394D02*
G03X128071Y421457I0J-3937D01*
G01X124134Y433268D02*
X283583D01*
G01X124134D02*
G03X120197Y429331I0J-3937D01*
G01X184173Y425394D02*
X132008D01*
G01X213480Y37075D02*
G03I-4291J0D01*
G01Y383483D02*
G03I-4291J0D01*
G01X184173Y425394D02*
G03Y433268I0J3937D01*
G01Y425394D02*
G03Y433268I0J3937D01*
G01X171457Y669291D02*
G03X154921I-8268J0D01*
G01D02*
G03X171457I8268J0D01*
G01X223543Y425394D02*
X275709D01*
G01X223543Y433268D02*
G03Y425394I0J-3937D01*
G01Y433268D02*
G03Y425394I0J-3937D01*
G01X275709Y0D02*
G03X279646Y3937I0J3937D01*
G01X291457Y0D02*
X921260D01*
G01X287520Y3937D02*
G03X291457Y0I3937J0D01*
G01X287520Y429331D02*
Y3937D01*
G01X279646Y59055D02*
Y3937D01*
G01X287520Y59055D02*
G03X279646I-3937J0D01*
G01X287520D02*
G03X279646I-3937J0D01*
G01Y98425D02*
Y421457D01*
G01Y98425D02*
G03X287520I3937J0D01*
G01X279646D02*
G03X287520I3937J0D01*
G01X315551Y157677D02*
G03X302559I-6496J0D01*
G01D02*
G03X315551I6496J0D01*
G01X315945Y406890D02*
G03Y420276I0J6693D01*
G01X302559D02*
X315945D01*
G01X302559D02*
G03Y406890I0J-6693D01*
G01X315945D02*
X302559D01*
G01X279646Y421457D02*
G03X275709Y425394I-3937J0D01*
G01X287520Y429331D02*
G03X283583Y433268I-3937J0D01*
G01X321850Y472441D02*
G03X308071I-6889J0D01*
G01D02*
G03X321850I6889J0D01*
G01X412402Y39370D02*
G03X398622I-6890J0D01*
G01D02*
G03X412402I6890J0D01*
G01X371063Y740157D02*
G03X357283I-6890J0D01*
G01D02*
G03X371063I6890J0D01*
G01X403756Y763780D02*
G03X400235Y758082I0J-3937D01*
G01X389671Y761603D02*
G03X386149Y763780I-3522J-1760D01*
G01X414895Y728762D02*
X400235Y758082D01*
G01X407852Y725241D02*
X389671Y761603D01*
G01X403756Y763780D02*
X428096D01*
G01X416142Y200787D02*
G03X420079Y196850I3937J0D01*
G01X408268Y188976D02*
Y723480D01*
G01Y188976D02*
G03X412205I1968J0D01*
G01X556299Y196850D02*
X420079D01*
G01X564173Y188976D02*
X412205D01*
G01X416142Y316929D02*
Y200787D01*
G01Y316929D02*
G03X408268I-3937J0D01*
G01X416142D02*
G03X408268I-3937J0D01*
G01X416142Y347638D02*
Y690803D01*
G01X408268Y347638D02*
G03X416142I3937J0D01*
G01X408268D02*
G03X416142I3937J0D01*
G01Y721512D02*
Y723481D01*
G01Y723482D02*
G03X414894Y728764I-11811J-2D01*
G01X408268Y723480D02*
G03X407852Y725241I-3937J0D01*
G01X408268Y721512D02*
G03X416142I3937J0D01*
G01Y690803D02*
G03X408268I-3937J0D01*
G01Y721512D02*
G03X416142I3937J0D01*
G01Y690803D02*
G03X408268I-3937J0D01*
G01X428096Y763780D02*
G03X435970I3937J0D01*
G01D02*
X572622D01*
G01X483800Y137224D02*
G03X493878I5039J0D01*
G01X493563Y164744D02*
G03X484115I-4724J0D01*
G01D02*
G03X493563I4724J0D01*
G01X493878Y137224D02*
G03X483800I-5039J0D01*
G01X493622Y245605D02*
G03I-4291J0D01*
G01Y698924D02*
G03I-4291J0D01*
G01X556299Y196850D02*
G03X560236Y200787I0J3937D01*
G01X564173Y188976D02*
G03X568110I1968J0D01*
G01Y723480D02*
Y188976D01*
G01X560236Y316929D02*
Y200787D01*
G01X568110Y316929D02*
G03X560236I-3937J0D01*
G01X568110D02*
G03X560236I-3937J0D01*
G01Y690803D02*
Y347638D01*
G01D02*
G03X568110I3937J0D01*
G01X560236D02*
G03X568110I3937J0D01*
G01X560236Y721512D02*
Y723481D01*
G01X561484Y728764D02*
G03X560236Y723482I10563J-5284D01*
G01X568526Y725241D02*
G03X568110Y723480I3521J-1761D01*
G01X560236Y721512D02*
G03X568110I3937J0D01*
G01Y690803D02*
G03X560236I-3937J0D01*
G01Y721512D02*
G03X568110I3937J0D01*
G01Y690803D02*
G03X560236I-3937J0D01*
G01X576143Y758082D02*
G03X572622Y763780I-3521J1761D01*
G01X576143Y758082D02*
X561483Y728762D01*
G01X586707Y761603D02*
X568526Y725241D01*
G01X590228Y763780D02*
G03X586707Y761603I1J-3937D01*
G01X903079Y763780D02*
X590228D01*
G01X634252Y57874D02*
G03X625591I-4331J0D01*
G01D02*
G03X634252I4331J0D01*
G01X658661Y180000D02*
G03X646850I-5905J0D01*
G01D02*
G03X658661I5906J0D01*
G01X619094Y433071D02*
G03X605315I-6889J0D01*
G01D02*
G03X619094I6890J0D01*
G01Y740157D02*
G03X605315I-6889J0D01*
G01D02*
G03X619094I6890J0D01*
G01X712992Y57874D02*
G03X704331I-4331J0D01*
G01D02*
G03X712992I4330J0D01*
G01X859449Y332598D02*
G03X871260I5905J0D01*
G01D02*
G03X859449I-5906J0D01*
G01X921260Y0D02*
G03X925197Y3937I0J3937D01*
G01X883858Y59055D02*
G03X868110I-7874J0D01*
G01D02*
G03X883858I7874J0D01*
G01X925197Y3937D02*
Y723480D01*
G01X882874Y433071D02*
G03X869094I-6890J0D01*
G01D02*
G03X882874I6890J0D01*
G01X925197Y723480D02*
G03X924781Y725241I-3937J0D01*
G01X882874Y740157D02*
G03X869094I-6890J0D01*
G01D02*
G03X882874I6890J0D01*
G01X906600Y761603D02*
G03X903079Y763780I-3522J-1760D01*
G01X924781Y725241D02*
X906600Y761603D01*
G54D12*
G01X83192Y557180D02*
X85815D01*
G01X83192Y555580D02*
X86135D01*
G01X83192D02*
X86135D01*
G01X83192Y557180D02*
X85815D01*
G01X629421Y89259D02*
X628502Y88340D01*
G01X631021Y88596D02*
X629450Y87025D01*
G01X629421Y91245D02*
Y89259D01*
G01X631021Y90582D02*
Y88596D01*
G01X634824Y96648D02*
X629421Y91245D01*
G01X635487Y95048D02*
X631021Y90582D01*
G01X640778Y96648D02*
X634824D01*
G01X641441Y95048D02*
X635487D01*
G01X651284Y107154D02*
X640778Y96648D01*
G01X652884Y106491D02*
X641441Y95048D01*
G01X651284Y125191D02*
Y107154D01*
G01X652884Y149647D02*
Y106491D01*
G01X651284Y130251D02*
Y128781D01*
G01X652884Y149647D02*
Y106491D01*
G01Y149647D02*
Y106491D01*
G01X631021Y88596D02*
X629450Y87025D01*
G01X629421Y89259D02*
X628502Y88340D01*
G01X631021Y90582D02*
Y88596D01*
G01X629421Y91245D02*
Y89259D01*
G01X635487Y95048D02*
X631021Y90582D01*
G01X634824Y96648D02*
X629421Y91245D01*
G01X641441Y95048D02*
X635487D01*
G01X640778Y96648D02*
X634824D01*
G01X652884Y106491D02*
X641441Y95048D01*
G01X651284Y107154D02*
X640778Y96648D01*
G01X652884Y149647D02*
Y106491D01*
G01X651284Y125191D02*
Y107154D01*
G01Y130251D02*
Y128781D01*
G01X638053Y88709D02*
X637542Y88436D01*
G01X639188Y87500D02*
X638584Y87177D01*
G01X639001Y90241D02*
X638053Y88709D01*
G01X640264Y89241D02*
X639188Y87500D01*
G01X640526Y91766D02*
X639001Y90241D01*
G01X641189Y90166D02*
X640264Y89241D01*
G01X645080Y91766D02*
X640526D01*
G01X645743Y90166D02*
X641189D01*
G01X649431Y96118D02*
X645080Y91766D01*
G01X658186Y102611D02*
X645743Y90166D01*
G01X653008Y99696D02*
X651969Y98656D01*
G01X658186Y102611D02*
X645743Y90166D01*
G01X656586Y103274D02*
X655547Y102234D01*
G01X658186Y102611D02*
X645743Y90166D01*
G01X656586Y149642D02*
Y103274D01*
G01X658186Y149748D02*
Y102611D01*
G01X639188Y87500D02*
X638584Y87177D01*
G01X638053Y88709D02*
X637542Y88436D01*
G01X640264Y89241D02*
X639188Y87500D01*
G01X639001Y90241D02*
X638053Y88709D01*
G01X641189Y90166D02*
X640264Y89241D01*
G01X640526Y91766D02*
X639001Y90241D01*
G01X645743Y90166D02*
X641189D01*
G01X645080Y91766D02*
X640526D01*
G01X658186Y102611D02*
X645743Y90166D01*
G01X649431Y96118D02*
X645080Y91766D01*
G01X653008Y99696D02*
X651969Y98656D01*
G01X656586Y103274D02*
X655547Y102234D01*
G01X658186Y149748D02*
Y102611D01*
G01X656586Y149642D02*
Y103274D01*
G01X629916Y74968D02*
X628934Y73610D01*
G01X630001Y72354D02*
X631516Y74449D01*
G01X629916Y76925D02*
Y74968D01*
G01X631516Y74449D02*
Y76262D01*
G01X634406Y81415D02*
X629916Y76925D01*
G01X631516Y76262D02*
X635069Y79815D01*
G01X643836Y81415D02*
X634406D01*
G01X635069Y79815D02*
X644499D01*
G01X654482Y92061D02*
X643836Y81415D01*
G01X644499Y79815D02*
X663312Y98628D01*
G01X657020Y94599D02*
X655521D01*
G01X644499Y79815D02*
X663312Y98628D01*
G01X658060Y95639D02*
X657020Y94599D01*
G01X644499Y79815D02*
X663312Y98628D01*
G01X660598Y98177D02*
X659099D01*
G01X644499Y79815D02*
X663312Y98628D01*
G01X661712Y99291D02*
X660598Y98177D01*
G01X644499Y79815D02*
X663312Y98628D01*
G01X661712Y149819D02*
Y99291D01*
G01X663312Y98628D02*
Y149775D01*
G01Y98628D02*
Y149775D01*
G01X661712Y149819D02*
Y99291D01*
G01X644499Y79815D02*
X663312Y98628D01*
G01X654482Y92061D02*
X643836Y81415D01*
G01X657020Y94599D02*
X655521D01*
G01X658060Y95639D02*
X657020Y94599D01*
G01X660598Y98177D02*
X659099D01*
G01X661712Y99291D02*
X660598Y98177D01*
G01X635069Y79815D02*
X644499D01*
G01X643836Y81415D02*
X634406D01*
G01X631516Y76262D02*
X635069Y79815D01*
G01X634406Y81415D02*
X629916Y76925D01*
G01X631516Y74449D02*
Y76262D01*
G01X629916Y76925D02*
Y74968D01*
G01X630001Y72354D02*
X631516Y74449D01*
G01X629916Y74968D02*
X628934Y73610D01*
G01X639302Y75466D02*
X637358Y73378D01*
G01X640473Y74375D02*
X638529Y72287D01*
G01X639321Y75486D02*
X639302Y75466D01*
G01X640473Y74375D02*
X638529Y72287D01*
G01X640135Y76300D02*
X639321Y75486D01*
G01X640798Y74700D02*
X640473Y74375D01*
G01X647098Y76300D02*
X640135D01*
G01X647761Y74700D02*
X640798D01*
G01X658666Y87868D02*
X647098Y76300D01*
G01X668731Y95670D02*
X647761Y74700D01*
G01X661205Y90407D02*
X659706D01*
G01X668731Y95670D02*
X647761Y74700D01*
G01X662244Y91446D02*
X661205Y90407D01*
G01X668731Y95670D02*
X647761Y74700D01*
G01X664783Y93985D02*
X663284D01*
G01X668731Y95670D02*
X647761Y74700D01*
G01X667131Y96333D02*
X664783Y93985D01*
G01X668731Y95670D02*
X647761Y74700D01*
G01X667131Y149801D02*
Y96333D01*
G01X640473Y74375D02*
X638529Y72287D01*
G01X639302Y75466D02*
X637358Y73378D01*
G01X639321Y75486D02*
X639302Y75466D01*
G01X640798Y74700D02*
X640473Y74375D01*
G01X640135Y76300D02*
X639321Y75486D01*
G01X647761Y74700D02*
X640798D01*
G01X647098Y76300D02*
X640135D01*
G01X668731Y95670D02*
X647761Y74700D01*
G01X658666Y87868D02*
X647098Y76300D01*
G01X661205Y90407D02*
X659706D01*
G01X662244Y91446D02*
X661205Y90407D01*
G01X664783Y93985D02*
X663284D01*
G01X667131Y96333D02*
X664783Y93985D01*
G01X667131Y149801D02*
Y96333D01*
G01X667084Y154584D02*
Y152846D01*
G01X668847Y156348D02*
X667552Y155053D01*
G01X662949Y172600D02*
X692081D01*
G01X663612Y171000D02*
X691926D01*
G01X651284Y160935D02*
X662949Y172600D01*
G01X652884Y160272D02*
X663612Y171000D01*
G01X651284Y152747D02*
Y160935D01*
G01X652884Y152847D02*
Y160272D01*
G01X663612Y171000D02*
X691926D01*
G01X662949Y172600D02*
X692081D01*
G01X652884Y160272D02*
X663612Y171000D01*
G01X651284Y160935D02*
X662949Y172600D01*
G01X652884Y152847D02*
Y160272D01*
G01X651284Y152747D02*
Y160935D01*
G01X664626Y167240D02*
X689409D01*
G01X665289Y165640D02*
X689250D01*
G01X656490Y159104D02*
X664626Y167240D01*
G01X658090Y158441D02*
X665289Y165640D01*
G01X656490Y152752D02*
Y159104D01*
G01X658090Y152842D02*
Y158441D01*
G01X665289Y165640D02*
X689250D01*
G01X664626Y167240D02*
X689409D01*
G01X658090Y158441D02*
X665289Y165640D01*
G01X656490Y159104D02*
X664626Y167240D01*
G01X658090Y152842D02*
Y158441D01*
G01X656490Y152752D02*
Y159104D01*
G01X667742Y162100D02*
X682655D01*
G01X661584Y155942D02*
X667742Y162100D01*
G01X663184Y155279D02*
X668405Y160500D01*
G01X661584Y152747D02*
Y155942D01*
G01X663184Y153047D02*
Y155279D01*
G01X667742Y162100D02*
X682655D01*
G01X663184Y155279D02*
X668405Y160500D01*
G01X661584Y155942D02*
X667742Y162100D01*
G01X663184Y153047D02*
Y155279D01*
G01X661584Y152747D02*
Y155942D01*
G01X667084Y154584D02*
Y152846D01*
G01X668847Y156348D02*
X667552Y155053D01*
G01X651284Y149747D02*
Y133841D01*
G01Y149747D02*
Y133841D01*
G01X708161Y89259D02*
X707242Y88340D01*
G01X709761Y88596D02*
X708190Y87025D01*
G01X708161Y91901D02*
Y89259D01*
G01X709761Y91238D02*
Y88596D01*
G01X713419Y97159D02*
X708161Y91901D01*
G01X714082Y95559D02*
X709761Y91238D01*
G01X720136Y97159D02*
X713419D01*
G01X720799Y95559D02*
X714082D01*
G01X724540Y101563D02*
X720136Y97159D01*
G01X725203Y99963D02*
X720799Y95559D01*
G01X753147Y101563D02*
X724540D01*
G01X737941Y99963D02*
X725203D01*
G01X709761Y88596D02*
X708190Y87025D01*
G01X708161Y89259D02*
X707242Y88340D01*
G01X709761Y91238D02*
Y88596D01*
G01X708161Y91901D02*
Y89259D01*
G01X714082Y95559D02*
X709761Y91238D01*
G01X713419Y97159D02*
X708161Y91901D01*
G01X720799Y95559D02*
X714082D01*
G01X720136Y97159D02*
X713419D01*
G01X725203Y99963D02*
X720799Y95559D01*
G01X724540Y101563D02*
X720136Y97159D01*
G01X737941Y99963D02*
X725203D01*
G01X753147Y101563D02*
X724540D01*
G01X753147D02*
X724540D01*
G01X724519Y93600D02*
X752500D01*
G01X725182Y92000D02*
X740487D01*
G01X722591Y91672D02*
X724519Y93600D01*
G01X723254Y90072D02*
X725182Y92000D01*
G01X718626Y91672D02*
X722591D01*
G01X719518Y90072D02*
X723254D01*
G01X716793Y88708D02*
X718626Y91672D01*
G01X717928Y87500D02*
X719518Y90072D01*
G01X716152Y88367D02*
X716793Y88708D01*
G01X716907Y86955D02*
X717928Y87500D01*
G01X716126Y88354D02*
X716152Y88367D01*
G01X716907Y86955D02*
X717928Y87500D01*
G01X716121Y88351D02*
X716126Y88354D01*
G01X716907Y86955D02*
X717928Y87500D01*
G01X716110Y88345D02*
X716115Y88348D01*
G01X716907Y86955D02*
X717928Y87500D01*
G01X724519Y93600D02*
X752500D01*
G01X725182Y92000D02*
X740487D01*
G01X724519Y93600D02*
X752500D01*
G01X723254Y90072D02*
X725182Y92000D01*
G01X722591Y91672D02*
X724519Y93600D01*
G01X719518Y90072D02*
X723254D01*
G01X718626Y91672D02*
X722591D01*
G01X717928Y87500D02*
X719518Y90072D01*
G01X716793Y88708D02*
X718626Y91672D01*
G01X716907Y86955D02*
X717928Y87500D01*
G01X716152Y88367D02*
X716793Y88708D01*
G01X716126Y88354D02*
X716152Y88367D01*
G01X716121Y88351D02*
X716126Y88354D01*
G01X716110Y88345D02*
X716115Y88348D01*
G01X708656Y74968D02*
X707674Y73610D01*
G01X710256Y74450D02*
X708741Y72354D01*
G01X708656Y76944D02*
Y74968D01*
G01X710256Y76281D02*
Y74450D01*
G01X713512Y81800D02*
X708656Y76944D01*
G01X714175Y80200D02*
X710256Y76281D01*
G01X721550Y81800D02*
X713512D01*
G01X722213Y80200D02*
X714175D01*
G01X725264Y85514D02*
X721550Y81800D01*
G01X725927Y83914D02*
X722213Y80200D01*
G01X753099Y85514D02*
X725264D01*
G01X743715Y83914D02*
X725927D01*
G01X710256Y74450D02*
X708741Y72354D01*
G01X708656Y74968D02*
X707674Y73610D01*
G01X710256Y76281D02*
Y74450D01*
G01X708656Y76944D02*
Y74968D01*
G01X714175Y80200D02*
X710256Y76281D01*
G01X713512Y81800D02*
X708656Y76944D01*
G01X722213Y80200D02*
X714175D01*
G01X721550Y81800D02*
X713512D01*
G01X725927Y83914D02*
X722213Y80200D01*
G01X725264Y85514D02*
X721550Y81800D01*
G01X743715Y83914D02*
X725927D01*
G01X753099Y85514D02*
X725264D01*
G01X753099D02*
X725264D01*
G01X718042Y75466D02*
X716098Y73378D01*
G01X719213Y74375D02*
X717269Y72287D01*
G01X718061Y75486D02*
X718042Y75466D01*
G01X719213Y74375D02*
X717269Y72287D01*
G01X718875Y76300D02*
X718061Y75486D01*
G01X719538Y74700D02*
X719213Y74375D01*
G01X723537Y76300D02*
X718875D01*
G01X724200Y74700D02*
X719538D01*
G01X724815Y77578D02*
X723537Y76300D01*
G01X725478Y75978D02*
X724200Y74700D01*
G01X753163Y77578D02*
X724815D01*
G01X745949Y75978D02*
X725478D01*
G01X719213Y74375D02*
X717269Y72287D01*
G01X718042Y75466D02*
X716098Y73378D01*
G01X718061Y75486D02*
X718042Y75466D01*
G01X719538Y74700D02*
X719213Y74375D01*
G01X718875Y76300D02*
X718061Y75486D01*
G01X724200Y74700D02*
X719538D01*
G01X723537Y76300D02*
X718875D01*
G01X725478Y75978D02*
X724200Y74700D01*
G01X724815Y77578D02*
X723537Y76300D01*
G01X745949Y75978D02*
X725478D01*
G01X753163Y77578D02*
X724815D01*
G01X753163D02*
X724815D01*
G01X668731Y149793D02*
Y95670D01*
G01Y149793D02*
Y95670D01*
G01X668684Y153921D02*
Y152948D01*
G01X669633Y154870D02*
X668684Y153921D01*
G01X673377Y155599D02*
X669633Y154870D01*
G01X673377Y157229D02*
X668847Y156348D01*
G01X733070Y144003D02*
X673377Y155599D01*
G01X681833Y155587D02*
X673377Y157229D01*
G01X686800Y154622D02*
X685357Y154902D01*
G01X691767Y153657D02*
X690324Y153937D01*
G01X696734Y152692D02*
X695291Y152972D01*
G01X719917Y148189D02*
X700258Y152008D01*
G01X724884Y147224D02*
X723441Y147505D01*
G01X729851Y146259D02*
X728408Y146540D01*
G01X734118Y143801D02*
X733070Y144004D01*
G01X735469Y145169D02*
X733375Y145575D01*
G01X735469Y145169D02*
X733375Y145575D01*
G01X729139Y165400D02*
X740698Y163154D01*
G01X724172Y166365D02*
X725615Y166084D01*
G01X691926Y171000D02*
X736925Y162257D01*
G01X719205Y167330D02*
X720648Y167050D01*
G01X691926Y171000D02*
X736925Y162257D01*
G01X692081Y172600D02*
X715681Y168015D01*
G01X691926Y171000D02*
X736925Y162257D01*
G01X729139Y165400D02*
X740698Y163154D01*
G01X691926Y171000D02*
X736925Y162257D01*
G01X724172Y166365D02*
X725615Y166084D01*
G01X719205Y167330D02*
X720648Y167050D01*
G01X692081Y172600D02*
X715681Y168015D01*
G01X725871Y159954D02*
X746335Y155864D01*
G01X689250Y165640D02*
X746335Y154232D01*
G01X720909Y160945D02*
X722350Y160657D01*
G01X689250Y165640D02*
X746335Y154232D01*
G01X715947Y161937D02*
X717388Y161649D01*
G01X689250Y165640D02*
X746335Y154232D01*
G01X710985Y162928D02*
X712427Y162640D01*
G01X689250Y165640D02*
X746335Y154232D01*
G01X689409Y167240D02*
X707465Y163632D01*
G01X689250Y165640D02*
X746335Y154232D01*
G01X689250Y165640D02*
X746335Y154232D01*
G01X725871Y159954D02*
X746335Y155864D01*
G01X720909Y160945D02*
X722350Y160657D01*
G01X715947Y161937D02*
X717388Y161649D01*
G01X710985Y162928D02*
X712427Y162640D01*
G01X689409Y167240D02*
X707465Y163632D01*
G01X699251Y158782D02*
X742789Y150075D01*
G01X682496Y160500D02*
X742789Y148443D01*
G01X694289Y159774D02*
X695731Y159485D01*
G01X682496Y160500D02*
X742789Y148443D01*
G01X689328Y160766D02*
X690769Y160477D01*
G01X682496Y160500D02*
X742789Y148443D01*
G01X682655Y162100D02*
X685807Y161470D01*
G01X682496Y160500D02*
X742789Y148443D01*
G01X668405Y160500D02*
X682496D01*
G01D02*
X742789Y148443D01*
G01X699251Y158782D02*
X742789Y150075D01*
G01X694289Y159774D02*
X695731Y159485D01*
G01X689328Y160766D02*
X690769Y160477D01*
G01X682655Y162100D02*
X685807Y161470D01*
G01X668405Y160500D02*
X682496D01*
G01X668684Y153921D02*
Y152948D01*
G01X669633Y154870D02*
X668684Y153921D01*
G01X673377Y157229D02*
X668847Y156348D01*
G01X673377Y155599D02*
X669633Y154870D01*
G01X681833Y155587D02*
X673377Y157229D01*
G01X733070Y144003D02*
X673377Y155599D01*
G01X686800Y154622D02*
X685357Y154902D01*
G01X733070Y144003D02*
X673377Y155599D01*
G01X691767Y153657D02*
X690324Y153937D01*
G01X733070Y144003D02*
X673377Y155599D01*
G01X696734Y152692D02*
X695291Y152972D01*
G01X733070Y144003D02*
X673377Y155599D01*
G01X719917Y148189D02*
X700258Y152008D01*
G01X733070Y144003D02*
X673377Y155599D01*
G01X724884Y147224D02*
X723441Y147505D01*
G01X733070Y144003D02*
X673377Y155599D01*
G01X729851Y146259D02*
X728408Y146540D01*
G01X733070Y144003D02*
X673377Y155599D01*
G01X735469Y145169D02*
X733375Y145575D01*
G01X734118Y143801D02*
X733070Y144004D01*
G01X772108Y101588D02*
X821559Y134941D01*
G01X772108Y101588D02*
X821559Y134941D01*
G01X772108Y101588D02*
X821559Y134941D01*
G01X772108Y101588D02*
X821559Y134941D01*
G01X789473Y115231D02*
X809847Y128973D01*
G01X772108Y101588D02*
X821559Y134941D01*
G01X789472Y115231D02*
X789473D01*
G01X772108Y101588D02*
X821559Y134941D01*
G01X788002Y115517D02*
X789472Y115231D01*
G01X772108Y101588D02*
X821559Y134941D01*
G01X785278Y112402D02*
X786497Y113224D01*
G01X772108Y101588D02*
X821559Y134941D01*
G01X783807Y112688D02*
X785278Y112402D01*
G01X772108Y101588D02*
X821559Y134941D01*
G01X781083Y109572D02*
X782302Y110394D01*
G01X772108Y101588D02*
X821559Y134941D01*
G01X779612Y109858D02*
X781083Y109572D01*
G01X772108Y101588D02*
X821559Y134941D01*
G01X771482Y103098D02*
X778107Y107565D01*
G01X772108Y101588D02*
X821559Y134941D01*
G01X764169Y101675D02*
X771483Y103097D01*
G01X764324Y100075D02*
X772108Y101588D01*
G01X756109Y101675D02*
X764169D01*
G01X756359Y100075D02*
X764324D01*
G01X772108Y101588D02*
X821559Y134941D01*
G01X789473Y115231D02*
X809847Y128973D01*
G01X789472Y115231D02*
X789473D01*
G01X788002Y115517D02*
X789472Y115231D01*
G01X785278Y112402D02*
X786497Y113224D01*
G01X783807Y112688D02*
X785278Y112402D01*
G01X781083Y109572D02*
X782302Y110394D01*
G01X779612Y109858D02*
X781083Y109572D01*
G01X771482Y103098D02*
X778107Y107565D01*
G01X764324Y100075D02*
X772108Y101588D01*
G01X764169Y101675D02*
X771483Y103097D01*
G01X756359Y100075D02*
X764324D01*
G01X756109Y101675D02*
X764169D01*
G01X763989Y93663D02*
X756122D01*
G01X764148Y92063D02*
X756348D01*
G01X778405Y96541D02*
X763989Y93663D01*
G01X779034Y95034D02*
X764148Y92063D01*
G01X783247Y99807D02*
X778405Y96541D01*
G01X799702Y108976D02*
X779034Y95035D01*
G01X786224Y101815D02*
X784752Y102101D01*
G01X799702Y108976D02*
X779034Y95035D01*
G01X787442Y102637D02*
X786224Y101815D01*
G01X799702Y108976D02*
X779034Y95035D01*
G01X790418Y104645D02*
X788947Y104931D01*
G01X799702Y108976D02*
X779034Y95035D01*
G01X791637Y105467D02*
X790418Y104645D01*
G01X799702Y108976D02*
X779034Y95035D01*
G01X794613Y107474D02*
X793142Y107760D01*
G01X799702Y108976D02*
X779034Y95035D01*
G01X795832Y108296D02*
X794613Y107474D01*
G01X799702Y108976D02*
X779034Y95035D01*
G01X798808Y110304D02*
X797337Y110590D01*
G01X799702Y108976D02*
X779034Y95035D01*
G01X811619Y118946D02*
X798808Y110304D01*
G01X764148Y92063D02*
X756348D01*
G01X763989Y93663D02*
X756122D01*
G01X779034Y95034D02*
X764148Y92063D01*
G01X778405Y96541D02*
X763989Y93663D01*
G01X799702Y108976D02*
X779034Y95035D01*
G01X783247Y99807D02*
X778405Y96541D01*
G01X786224Y101815D02*
X784752Y102101D01*
G01X787442Y102637D02*
X786224Y101815D01*
G01X790418Y104645D02*
X788947Y104931D01*
G01X791637Y105467D02*
X790418Y104645D01*
G01X794613Y107474D02*
X793142Y107760D01*
G01X795832Y108296D02*
X794613Y107474D01*
G01X798808Y110304D02*
X797337Y110590D01*
G01X811619Y118946D02*
X798808Y110304D01*
G01X776705Y85349D02*
X833868Y123452D01*
G01X776705Y85349D02*
X833868Y123452D01*
G01X776705Y85349D02*
X833868Y123452D01*
G01X776705Y85349D02*
X833868Y123452D01*
G01X797809Y101340D02*
X812658Y111238D01*
G01X776705Y85349D02*
X833868Y123452D01*
G01X793598Y98534D02*
X794821Y99349D01*
G01X776705Y85349D02*
X833868Y123452D01*
G01X792128Y98828D02*
X793598Y98534D01*
G01X776705Y85349D02*
X833868Y123452D01*
G01X789388Y95727D02*
X790611Y96543D01*
G01X776705Y85349D02*
X833868Y123452D01*
G01X785177Y92921D02*
X786401Y93736D01*
G01X776705Y85349D02*
X833868Y123452D01*
G01X783707Y93215D02*
X785177Y92921D01*
G01X776705Y85349D02*
X833868Y123452D01*
G01X776084Y86860D02*
X782190Y90930D01*
G01X776705Y85349D02*
X833868Y123452D01*
G01X769094Y85500D02*
X776084Y86859D01*
G01X769249Y83900D02*
X776705Y85349D01*
G01X756284Y85500D02*
X769094D01*
G01X756185Y83900D02*
X769249D01*
G01X776705Y85349D02*
X833868Y123452D01*
G01X797809Y101340D02*
X812658Y111238D01*
G01X793598Y98534D02*
X794821Y99349D01*
G01X792128Y98828D02*
X793598Y98534D01*
G01X789388Y95727D02*
X790611Y96543D01*
G01X785177Y92921D02*
X786401Y93736D01*
G01X783707Y93215D02*
X785177Y92921D01*
G01X776084Y86860D02*
X782190Y90930D01*
G01X769249Y83900D02*
X776705Y85349D01*
G01X769094Y85500D02*
X776084Y86859D01*
G01X756185Y83900D02*
X769249D01*
G01X756284Y85500D02*
X769094D01*
G01X772706Y77382D02*
X756403D01*
G01X773191Y75782D02*
X756067D01*
G01X786599Y86640D02*
X772706Y77382D01*
G01X802554Y95349D02*
X773191Y75782D01*
G01X790810Y89446D02*
X789587Y88631D01*
G01X802554Y95349D02*
X773191Y75782D01*
G01X793797Y91437D02*
X792327Y91731D01*
G01X802554Y95349D02*
X773191Y75782D01*
G01X795021Y92252D02*
X793797Y91437D01*
G01X802554Y95349D02*
X773191Y75782D01*
G01X799231Y95058D02*
X798008Y94243D01*
G01X802554Y95349D02*
X773191Y75782D01*
G01D02*
X756067D01*
G01X772706Y77382D02*
X756403D01*
G01X802554Y95349D02*
X773191Y75782D01*
G01X786599Y86640D02*
X772706Y77382D01*
G01X790810Y89446D02*
X789587Y88631D01*
G01X793797Y91437D02*
X792327Y91731D01*
G01X795021Y92252D02*
X793797Y91437D01*
G01X799231Y95058D02*
X798008Y94243D01*
G01X753121Y99963D02*
X741531D01*
G01X753121D02*
X741531D01*
G01X744077Y92000D02*
X752400D01*
G01X744077D02*
X752400D01*
G01X753171Y83914D02*
X747305D01*
G01X753171D02*
X747305D01*
G01X753106Y75978D02*
X749539D01*
G01X753106D02*
X749539D01*
G01X735164Y143598D02*
X734118Y143801D01*
G01X738337Y142981D02*
X735164Y143598D01*
G01X738642Y144552D02*
X735469Y145169D01*
G01X739973Y142663D02*
X738337Y142981D01*
G01X739969Y144294D02*
X738642Y144552D01*
G01X813960Y157466D02*
X739973Y142663D01*
G01X739969Y144294D02*
X738642Y144552D01*
G01X813294Y158965D02*
X739969Y144294D01*
G01X749173Y161506D02*
X804908Y172744D01*
G01X777357Y165556D02*
X805538Y171238D01*
G01X749179Y159874D02*
X777357Y165556D01*
G01X740698Y163154D02*
X749173Y161506D01*
G01X745762Y160539D02*
X749179Y159874D01*
G01X741550Y161358D02*
X745762Y160539D01*
G01X736925Y162257D02*
X741550Y161358D01*
G01X777357Y165556D02*
X805538Y171238D01*
G01X749173Y161506D02*
X804908Y172744D01*
G01X749179Y159874D02*
X777357Y165556D01*
G01X749173Y161506D02*
X804908Y172744D01*
G01X745762Y160539D02*
X749179Y159874D01*
G01X740698Y163154D02*
X749173Y161506D01*
G01X741550Y161358D02*
X745762Y160539D01*
G01X740698Y163154D02*
X749173Y161506D01*
G01X736925Y162257D02*
X741550Y161358D01*
G01X746335Y155864D02*
X808964Y168396D01*
G01X746335Y154232D02*
X809631Y166897D01*
G01X746335Y154232D02*
X809631Y166897D01*
G01X746335Y155864D02*
X808964Y168396D01*
G01X742789Y150075D02*
X811247Y163770D01*
G01X742789Y148443D02*
X811917Y162272D01*
G01X742789Y148443D02*
X811917Y162272D01*
G01X742789Y150075D02*
X811247Y163770D01*
G01X735164Y143598D02*
X734118Y143801D01*
G01X738642Y144552D02*
X735469Y145169D01*
G01X738337Y142981D02*
X735164Y143598D01*
G01X739969Y144294D02*
X738642Y144552D01*
G01X739973Y142663D02*
X738337Y142981D01*
G01X813960Y157466D02*
X739973Y142663D01*
G01X813294Y158965D02*
X739969Y144294D01*
G01X813960Y157466D02*
X739973Y142663D01*
G01X817018Y133810D02*
X818237Y134632D01*
G01X815546Y134096D02*
X817018Y133810D01*
G01X812823Y130980D02*
X814042Y131802D01*
G01X811351Y131266D02*
X812823Y130980D01*
G01X817018Y133810D02*
X818237Y134632D01*
G01X815546Y134096D02*
X817018Y133810D01*
G01X812823Y130980D02*
X814042Y131802D01*
G01X811351Y131266D02*
X812823Y130980D01*
G01X823879Y125284D02*
X799702Y108976D01*
G01X814596Y120953D02*
X813124Y121239D01*
G01X823879Y125284D02*
X799702Y108976D01*
G01X815814Y121775D02*
X814596Y120953D01*
G01X823879Y125284D02*
X799702Y108976D01*
G01X818791Y123783D02*
X817319Y124069D01*
G01X823879Y125284D02*
X799702Y108976D01*
G01X820009Y124605D02*
X818791Y123783D01*
G01X823879Y125284D02*
X799702Y108976D01*
G01X822985Y126612D02*
X821514Y126898D01*
G01X823879Y125284D02*
X799702Y108976D01*
G01X828399Y130264D02*
X822985Y126612D01*
G01X829552Y129111D02*
X823879Y125285D01*
G01X835270Y140450D02*
X828399Y130264D01*
G01X848490Y157186D02*
X829552Y129111D01*
G01X848490Y157186D02*
X829552Y129111D01*
G01X848490Y157186D02*
X829552Y129111D01*
G01X848490Y157186D02*
X829552Y129111D01*
G01X823879Y125284D02*
X799702Y108976D01*
G01X814596Y120953D02*
X813124Y121239D01*
G01X815814Y121775D02*
X814596Y120953D01*
G01X818791Y123783D02*
X817319Y124069D01*
G01X820009Y124605D02*
X818791Y123783D01*
G01X822985Y126612D02*
X821514Y126898D01*
G01X829552Y129111D02*
X823879Y125285D01*
G01X828399Y130264D02*
X822985Y126612D01*
G01X848490Y157186D02*
X829552Y129111D01*
G01X835270Y140450D02*
X828399Y130264D01*
G01X832714Y124606D02*
X851666Y153035D01*
G01X833868Y123452D02*
X853173Y152411D01*
G01X824066Y118842D02*
X832714Y124606D01*
G01X822596Y119136D02*
X824066Y118842D01*
G01X819855Y116035D02*
X821078Y116850D01*
G01X815645Y113229D02*
X816868Y114044D01*
G01X833868Y123452D02*
X853173Y152411D01*
G01X832714Y124606D02*
X851666Y153035D01*
G01X824066Y118842D02*
X832714Y124606D01*
G01X822596Y119136D02*
X824066Y118842D01*
G01X819855Y116035D02*
X821078Y116850D01*
G01X815645Y113229D02*
X816868Y114044D01*
G01X820910Y109505D02*
X802218Y97049D01*
G01X832655Y115408D02*
X802554Y95349D01*
G01X825120Y112311D02*
X823897Y111496D01*
G01X832655Y115408D02*
X802554Y95349D01*
G01X828108Y114302D02*
X826638Y114596D01*
G01X832655Y115408D02*
X802554Y95349D01*
G01X829331Y115117D02*
X828108Y114302D01*
G01X832655Y115408D02*
X802554Y95349D01*
G01X832319Y117108D02*
X830849Y117402D01*
G01X836982Y118292D02*
X832655Y115409D01*
G01X835828Y119446D02*
X832319Y117108D01*
G01X836982Y118292D02*
X832655Y115409D01*
G01X856101Y149862D02*
X835828Y119446D01*
G01X857608Y149238D02*
X836982Y118292D01*
G01X832655Y115408D02*
X802554Y95349D01*
G01X820910Y109505D02*
X802218Y97049D01*
G01X825120Y112311D02*
X823897Y111496D01*
G01X828108Y114302D02*
X826638Y114596D01*
G01X829331Y115117D02*
X828108Y114302D01*
G01X836982Y118292D02*
X832655Y115409D01*
G01X832319Y117108D02*
X830849Y117402D01*
G01X835828Y119446D02*
X832319Y117108D01*
G01X857608Y149238D02*
X836982Y118292D01*
G01X856101Y149862D02*
X835828Y119446D01*
G01X842418Y163289D02*
X857175Y239217D01*
G01X843927Y162664D02*
X858805Y239217D01*
G01X827143Y140639D02*
X842418Y163289D01*
G01X828296Y139486D02*
X843927Y162664D01*
G01X821213Y136639D02*
X827143Y140639D01*
G01X821559Y134941D02*
X828296Y139486D01*
G01X819741Y136925D02*
X821213Y136639D01*
G01X821559Y134941D02*
X828296Y139486D01*
G01X843927Y162664D02*
X858805Y239217D01*
G01X842418Y163289D02*
X857175Y239217D01*
G01X828296Y139486D02*
X843927Y162664D01*
G01X827143Y140639D02*
X842418Y163289D01*
G01X821559Y134941D02*
X828296Y139486D01*
G01X821213Y136639D02*
X827143Y140639D01*
G01X819741Y136925D02*
X821213Y136639D01*
G01X838100Y144645D02*
X837277Y143426D01*
G01X840929Y148839D02*
X840107Y147621D01*
G01X846981Y157811D02*
X842937Y151817D01*
G01X862748Y238917D02*
X846981Y157811D01*
G01X864379Y238921D02*
X848490Y157186D01*
G01X838100Y144645D02*
X837277Y143426D01*
G01X840929Y148839D02*
X840107Y147621D01*
G01X846981Y157811D02*
X842937Y151817D01*
G01X864379Y238921D02*
X848490Y157186D01*
G01X862748Y238917D02*
X846981Y157811D01*
G01X851666Y153035D02*
X868314Y236289D01*
G01X853173Y152411D02*
X869946Y236289D01*
G01X853173Y152411D02*
X869946Y236289D01*
G01X851666Y153035D02*
X868314Y236289D01*
G01X873361Y236171D02*
X856101Y149862D01*
G01X874993Y236171D02*
X857608Y149238D01*
G01X874993Y236171D02*
X857608Y149238D01*
G01X873361Y236171D02*
X856101Y149862D01*
G01X836836Y174464D02*
X813960Y157466D01*
G01X835662Y175586D02*
X813294Y158965D01*
G01X842229Y182460D02*
X836836Y174464D01*
G01X840723Y183089D02*
X835662Y175586D01*
G01X844988Y196259D02*
X842229Y182460D01*
G01X846115Y210057D02*
X840723Y183089D01*
G01X853140Y237025D02*
X844988Y196259D01*
G01X823632Y185380D02*
X834543Y239863D01*
G01X825072Y184421D02*
X836175Y239863D01*
G01X804908Y172744D02*
X823632Y185380D01*
G01X805538Y171238D02*
X825072Y184421D01*
G01D02*
X836175Y239863D01*
G01X823632Y185380D02*
X834543Y239863D01*
G01X805538Y171238D02*
X825072Y184421D01*
G01X804908Y172744D02*
X823632Y185380D01*
G01X832708Y186902D02*
X842546Y236075D01*
G01X832708Y186902D02*
X842546Y236075D01*
G01X832708Y186902D02*
X842546Y236075D01*
G01X831202Y187531D02*
X837871Y220868D01*
G01X832708Y186902D02*
X842546Y236075D01*
G01X827676Y182307D02*
X831202Y187531D01*
G01X828850Y181186D02*
X832708Y186902D01*
G01X808964Y168396D02*
X827676Y182307D01*
G01X809631Y166897D02*
X828850Y181186D01*
G01X832708Y186902D02*
X842546Y236075D01*
G01X831202Y187531D02*
X837871Y220868D01*
G01X828850Y181186D02*
X832708Y186902D01*
G01X827676Y182307D02*
X831202Y187531D01*
G01X809631Y166897D02*
X828850Y181186D01*
G01X808964Y168396D02*
X827676Y182307D01*
G01X836007Y185489D02*
X846434Y237630D01*
G01X837513Y184860D02*
X842790Y211246D01*
G01X831718Y179130D02*
X836007Y185489D01*
G01X832894Y178012D02*
X837513Y184860D01*
G01X811247Y163770D02*
X831718Y179130D01*
G01X811917Y162272D02*
X832894Y178012D01*
G01X836007Y185489D02*
X846434Y237630D01*
G01X837513Y184860D02*
X842790Y211246D01*
G01X836007Y185489D02*
X846434Y237630D01*
G01X832894Y178012D02*
X837513Y184860D01*
G01X831718Y179130D02*
X836007Y185489D01*
G01X811917Y162272D02*
X832894Y178012D01*
G01X811247Y163770D02*
X831718Y179130D01*
G01X835662Y175586D02*
X813294Y158965D01*
G01X836836Y174464D02*
X813960Y157466D01*
G01X840723Y183089D02*
X835662Y175586D01*
G01X842229Y182460D02*
X836836Y174464D01*
G01X846115Y210057D02*
X840723Y183089D01*
G01X844988Y196259D02*
X842229Y182460D01*
G01X853140Y237025D02*
X844988Y196259D01*
G01X857175Y239217D02*
X851548Y268187D01*
G01X858805Y239217D02*
X853026Y268973D01*
G01X858805Y239217D02*
X853026Y268973D01*
G01X857175Y239217D02*
X851548Y268187D01*
G01X855358Y275878D02*
X862748Y238917D01*
G01X856832Y276667D02*
X864379Y238921D01*
G01X856832Y276667D02*
X864379Y238921D01*
G01X855358Y275878D02*
X862748Y238917D01*
G01X868314Y236289D02*
X858451Y285549D01*
G01X869946Y236289D02*
X859925Y286338D01*
G01X869946Y236289D02*
X859925Y286338D01*
G01X868314Y236289D02*
X858451Y285549D01*
G01X851508Y237025D02*
X846115Y210057D01*
G01X847807Y263693D02*
X853140Y237025D01*
G01X848921Y249963D02*
X851508Y237025D01*
G01X846333Y262904D02*
X848921Y249963D01*
G01X828300Y283200D02*
X847807Y263693D01*
G01X827637Y281600D02*
X846333Y262904D01*
G01X817487Y262618D02*
X816141D01*
G01X818150Y264218D02*
X816141D01*
G01X824000Y256105D02*
X817487Y262618D01*
G01X825600Y256768D02*
X818150Y264218D01*
G01X834128Y241940D02*
X824000Y252068D01*
G01X825602Y252730D02*
X825601D01*
G01X835603Y242729D02*
X825602Y252730D01*
G01X834262Y241267D02*
X834128Y241940D01*
G01X835852Y241480D02*
X835603Y242729D01*
G01X834304Y241060D02*
X834262Y241267D01*
G01X836175Y239863D02*
X835873Y241375D01*
G01X834543Y239863D02*
X834304Y241060D01*
G01X835873Y241375D02*
X835852Y241480D01*
G01X836175Y239863D02*
X835873Y241375D01*
G01X818150Y264218D02*
X816141D01*
G01X817487Y262618D02*
X816141D01*
G01X825600Y256768D02*
X818150Y264218D01*
G01X824000Y256105D02*
X817487Y262618D01*
G01X825602Y252730D02*
X825601D01*
G01X834128Y241940D02*
X824000Y252068D01*
G01X835603Y242729D02*
X825602Y252730D01*
G01X834128Y241940D02*
X824000Y252068D01*
G01X835852Y241480D02*
X835603Y242729D01*
G01X834262Y241267D02*
X834128Y241940D01*
G01X835873Y241375D02*
X835852Y241480D01*
G01X834543Y239863D02*
X834304Y241060D01*
G01X836175Y239863D02*
X835873Y241375D01*
G01X834304Y241060D02*
X834262Y241267D01*
G01X834543Y239863D02*
X834304Y241060D01*
G01X835327Y251597D02*
X819516Y267408D01*
G01X836556Y252631D02*
X820179Y269008D01*
G01X838792Y246681D02*
X835327Y251597D01*
G01X836635Y252519D02*
X836556Y252631D01*
G01X838368Y250061D02*
X836635Y252519D01*
G01X840295Y247326D02*
X838368Y250061D01*
G01X840914Y236075D02*
X838792Y246681D01*
G01X840362Y246995D02*
X840295Y247326D01*
G01X842546Y236075D02*
X840361Y246995D01*
G01X840561Y234311D02*
X840914Y236075D01*
G01X839568Y229350D02*
X839857Y230791D01*
G01X838576Y224388D02*
X838864Y225830D01*
G01X836556Y252631D02*
X820179Y269008D01*
G01X835327Y251597D02*
X819516Y267408D01*
G01X836635Y252519D02*
X836556Y252631D01*
G01X838792Y246681D02*
X835327Y251597D01*
G01X838368Y250061D02*
X836635Y252519D01*
G01X838792Y246681D02*
X835327Y251597D01*
G01X840295Y247326D02*
X838368Y250061D01*
G01X838792Y246681D02*
X835327Y251597D01*
G01X840362Y246995D02*
X840295Y247326D01*
G01X840914Y236075D02*
X838792Y246681D01*
G01X842546Y236075D02*
X840361Y246995D01*
G01X840914Y236075D02*
X838792Y246681D01*
G01X840561Y234311D02*
X840914Y236075D01*
G01X839568Y229350D02*
X839857Y230791D01*
G01X838576Y224388D02*
X838864Y225830D01*
G01X839549Y256485D02*
X820876Y275158D01*
G01X840793Y257504D02*
X821539Y276758D01*
G01X844000Y249800D02*
X839549Y256485D01*
G01X843107Y254029D02*
X840793Y257504D01*
G01X845507Y250424D02*
X843107Y254029D01*
G01X846434Y237630D02*
X844000Y249800D01*
G01X846787Y244029D02*
X845507Y250424D01*
G01X847396Y240985D02*
X846786Y244029D01*
G01X847699Y239464D02*
X847396Y240985D01*
G01X848066Y237630D02*
X847699Y239464D01*
G01X842790Y211246D02*
X848066Y237630D01*
G01X840793Y257504D02*
X821539Y276758D01*
G01X839549Y256485D02*
X820876Y275158D01*
G01X843107Y254029D02*
X840793Y257504D01*
G01X844000Y249800D02*
X839549Y256485D01*
G01X845507Y250424D02*
X843107Y254029D01*
G01X844000Y249800D02*
X839549Y256485D01*
G01X846787Y244029D02*
X845507Y250424D01*
G01X846434Y237630D02*
X844000Y249800D01*
G01X847396Y240985D02*
X846786Y244029D01*
G01X846434Y237630D02*
X844000Y249800D01*
G01X847699Y239464D02*
X847396Y240985D01*
G01X846434Y237630D02*
X844000Y249800D01*
G01X848066Y237630D02*
X847699Y239464D01*
G01X846434Y237630D02*
X844000Y249800D01*
G01X842790Y211246D02*
X848066Y237630D01*
G01X851508Y237025D02*
X846115Y210057D01*
G01X848921Y249963D02*
X851508Y237025D01*
G01X847807Y263693D02*
X853140Y237025D01*
G01X846333Y262904D02*
X848921Y249963D01*
G01X847807Y263693D02*
X853140Y237025D01*
G01X827637Y281600D02*
X846333Y262904D01*
G01X828300Y283200D02*
X847807Y263693D01*
G01X807163Y283570D02*
X805740D01*
G01X806500Y285170D02*
X805740D01*
G01X809983Y286390D02*
X807163Y283570D01*
G01X809320Y287990D02*
X806500Y285170D01*
G01X833346Y286390D02*
X809983D01*
G01X834009Y287990D02*
X809320D01*
G01X851548Y268187D02*
X833346Y286390D01*
G01X853026Y268973D02*
X834009Y287990D01*
G01X806500Y285170D02*
X805740D01*
G01X807163Y283570D02*
X805740D01*
G01X809320Y287990D02*
X806500Y285170D01*
G01X809983Y286390D02*
X807163Y283570D01*
G01X834009Y287990D02*
X809320D01*
G01X833346Y286390D02*
X809983D01*
G01X853026Y268973D02*
X834009Y287990D01*
G01X851548Y268187D02*
X833346Y286390D01*
G01X838736Y292500D02*
X855358Y275878D01*
G01X839399Y294100D02*
X856832Y276667D01*
G01X815911Y292500D02*
X838736D01*
G01X815911Y294100D02*
X839399D01*
G01D02*
X856832Y276667D01*
G01X838736Y292500D02*
X855358Y275878D01*
G01X815911Y294100D02*
X839399D01*
G01X815911Y292500D02*
X838736D01*
G01X809988Y295935D02*
X804557D01*
G01X809325Y297535D02*
X804557D01*
G01X812308Y298255D02*
X809988Y295935D01*
G01X811645Y299855D02*
X809325Y297535D01*
G01X845745Y298255D02*
X812308D01*
G01X846408Y299855D02*
X811645D01*
G01X858451Y285549D02*
X845745Y298255D01*
G01X859925Y286338D02*
X846408Y299855D01*
G01X809325Y297535D02*
X804557D01*
G01X809988Y295935D02*
X804557D01*
G01X811645Y299855D02*
X809325Y297535D01*
G01X812308Y298255D02*
X809988Y295935D01*
G01X846408Y299855D02*
X811645D01*
G01X845745Y298255D02*
X812308D01*
G01X859925Y286338D02*
X846408Y299855D01*
G01X858451Y285549D02*
X845745Y298255D01*
G01X861929Y293370D02*
X873361Y236171D01*
G01X863403Y294159D02*
X874993Y236171D01*
G01X852154Y303145D02*
X861929Y293370D01*
G01X852817Y304745D02*
X863403Y294159D01*
G01X807798Y303145D02*
X852154D01*
G01X807135Y304745D02*
X852817D01*
G01X804843Y300190D02*
X807798Y303145D01*
G01X804180Y301790D02*
X807135Y304745D01*
G01X802950Y300190D02*
X804843D01*
G01X802950Y301790D02*
X804180D01*
G01X863403Y294159D02*
X874993Y236171D01*
G01X861929Y293370D02*
X873361Y236171D01*
G01X852817Y304745D02*
X863403Y294159D01*
G01X852154Y303145D02*
X861929Y293370D01*
G01X807135Y304745D02*
X852817D01*
G01X807798Y303145D02*
X852154D01*
G01X804180Y301790D02*
X807135Y304745D01*
G01X804843Y300190D02*
X807798Y303145D01*
G01X802950Y301790D02*
X804180D01*
G01X802950Y300190D02*
X804843D01*
G01X812360Y283200D02*
X828300D01*
G01X812360Y281600D02*
X827637D01*
G01X819516Y267408D02*
X816141D01*
G01X820179Y269008D02*
X816141D01*
G01X820179D02*
X816141D01*
G01X819516Y267408D02*
X816141D01*
G01X820876Y275158D02*
X811498D01*
G01X821539Y276758D02*
X811498D01*
G01X821539D02*
X811498D01*
G01X820876Y275158D02*
X811498D01*
G01X812360Y281600D02*
X827637D01*
G01X812360Y283200D02*
X828300D01*
G54D13*
G01X345519Y207631D02*
X337465Y249072D01*
G01X345519Y207631D02*
X337465Y249072D01*
G01X345519Y207631D02*
X337465Y249072D01*
G01X339875Y243092D02*
X340204Y241399D01*
G01X345519Y207631D02*
X337465Y249072D01*
G01X338713Y249071D02*
X339317Y245964D01*
G01X345519Y207631D02*
X337465Y249072D01*
G01X340482Y258172D02*
X338713Y249071D01*
G01X337465Y249072D02*
X339233Y258172D01*
G01X339879Y261267D02*
X340482Y258172D01*
G01X339233D02*
X338234Y263302D01*
G01X339366Y263904D02*
X339879Y261267D01*
G01X339233Y258172D02*
X338234Y263302D01*
G01X336395Y266874D02*
X339366Y263904D01*
G01X338234Y263302D02*
X335887Y265649D01*
G01X327837Y262454D02*
X332257Y266874D01*
G01X332765Y265649D02*
X328345Y261229D01*
G01X317813Y262454D02*
X327837D01*
G01X328345Y261229D02*
X309021D01*
G01X313163Y262454D02*
X314888D01*
G01X328345Y261229D02*
X309021D01*
G01X308513Y262454D02*
X310238D01*
G01X328345Y261229D02*
X309021D01*
G01X304933Y258874D02*
X308513Y262454D01*
G01X309021Y261229D02*
X305441Y257649D01*
G01X303282Y258874D02*
X304933D01*
G01X305441Y257649D02*
X302774D01*
G01X301944Y260212D02*
X303282Y258874D01*
G01X302774Y257649D02*
X300719Y259704D01*
G01X301944Y265610D02*
Y260212D01*
G01X300719Y259704D02*
Y266118D01*
G01Y259704D02*
Y266118D01*
G01X301944Y265610D02*
Y260212D01*
G01X302774Y257649D02*
X300719Y259704D01*
G01X301944Y260212D02*
X303282Y258874D01*
G01X305441Y257649D02*
X302774D01*
G01X303282Y258874D02*
X304933D01*
G01X309021Y261229D02*
X305441Y257649D01*
G01X304933Y258874D02*
X308513Y262454D01*
G01X328345Y261229D02*
X309021D01*
G01X317813Y262454D02*
X327837D01*
G01X313163D02*
X314888D01*
G01X308513D02*
X310238D01*
G01X332765Y265649D02*
X328345Y261229D01*
G01X327837Y262454D02*
X332257Y266874D01*
G01X338234Y263302D02*
X335887Y265649D01*
G01X336395Y266874D02*
X339366Y263904D01*
G01X339233Y258172D02*
X338234Y263302D01*
G01X339879Y261267D02*
X340482Y258172D01*
G01X339366Y263904D02*
X339879Y261267D01*
G01X337465Y249072D02*
X339233Y258172D01*
G01X340482D02*
X338713Y249071D01*
G01X345519Y207631D02*
X337465Y249072D01*
G01X339875Y243092D02*
X340204Y241399D01*
G01X338713Y249071D02*
X339317Y245964D01*
G01X317938Y329229D02*
X308704D01*
G01X317430Y330454D02*
X308705D01*
G01X319433Y330723D02*
X317938Y329229D01*
G01X318566Y331590D02*
X317430Y330454D01*
G01X333653Y326527D02*
X327533Y332647D01*
G01X334161Y327752D02*
X328041Y333872D01*
G01X340373Y326527D02*
X333653D01*
G01X340881Y327752D02*
X334161D01*
G01X354618Y312282D02*
X340373Y326527D01*
G01X317430Y330454D02*
X308705D01*
G01X317938Y329229D02*
X308704D01*
G01X318566Y331590D02*
X317430Y330454D01*
G01X319433Y330723D02*
X317938Y329229D01*
G01X334161Y327752D02*
X328041Y333872D01*
G01X333653Y326527D02*
X327533Y332647D01*
G01X340881Y327752D02*
X334161D01*
G01X340373Y326527D02*
X333653D01*
G01X354618Y312282D02*
X340373Y326527D01*
G01X317194Y316529D02*
X305082D01*
G01X317702Y317754D02*
X305082D01*
G01X320194Y313529D02*
X317194Y316529D01*
G01X320702Y314754D02*
X317702Y317754D01*
G01X328716Y313529D02*
X320194D01*
G01X328208Y314754D02*
X320702D01*
G01X333581Y318394D02*
X328716Y313529D01*
G01X333073Y319619D02*
X328208Y314754D01*
G01X341006Y318394D02*
X333581D01*
G01X341514Y319619D02*
X333073D01*
G01X317702Y317754D02*
X305082D01*
G01X317194Y316529D02*
X305082D01*
G01X320702Y314754D02*
X317702Y317754D01*
G01X320194Y313529D02*
X317194Y316529D01*
G01X328208Y314754D02*
X320702D01*
G01X328716Y313529D02*
X320194D01*
G01X333073Y319619D02*
X328208Y314754D01*
G01X333581Y318394D02*
X328716Y313529D01*
G01X341514Y319619D02*
X333073D01*
G01X341006Y318394D02*
X333581D01*
G01X318737Y303929D02*
X308704D01*
G01X318229Y305154D02*
X308705D01*
G01X321119Y306311D02*
X318737Y303929D01*
G01X320611Y307536D02*
X318229Y305154D01*
G01X328513Y306311D02*
X321119D01*
G01X329021Y307536D02*
X320611D01*
G01X332887Y301937D02*
X328513Y306311D01*
G01X333395Y303162D02*
X329021Y307536D01*
G01X342163Y301937D02*
X332887D01*
G01X342671Y303162D02*
X333395D01*
G01X318229Y305154D02*
X308705D01*
G01X318737Y303929D02*
X308704D01*
G01X320611Y307536D02*
X318229Y305154D01*
G01X321119Y306311D02*
X318737Y303929D01*
G01X329021Y307536D02*
X320611D01*
G01X328513Y306311D02*
X321119D01*
G01X333395Y303162D02*
X329021Y307536D01*
G01X332887Y301937D02*
X328513Y306311D01*
G01X342671Y303162D02*
X333395D01*
G01X342163Y301937D02*
X332887D01*
G01X317694Y291329D02*
X305182D01*
G01X318202Y292554D02*
X305182D01*
G01X320422Y288601D02*
X317694Y291329D01*
G01X320930Y289826D02*
X318202Y292554D01*
G01X328783Y288601D02*
X320422D01*
G01X328275Y289826D02*
X320930D01*
G01X333406Y293224D02*
X328783Y288601D01*
G01X332898Y294449D02*
X328275Y289826D01*
G01X338976Y293224D02*
X333406D01*
G01X339484Y294449D02*
X332898D01*
G01X345872Y286328D02*
X338976Y293224D01*
G01X347001Y286932D02*
X339484Y294449D01*
G01X318202Y292554D02*
X305182D01*
G01X317694Y291329D02*
X305182D01*
G01X320930Y289826D02*
X318202Y292554D01*
G01X320422Y288601D02*
X317694Y291329D01*
G01X328275Y289826D02*
X320930D01*
G01X328783Y288601D02*
X320422D01*
G01X332898Y294449D02*
X328275Y289826D01*
G01X333406Y293224D02*
X328783Y288601D01*
G01X339484Y294449D02*
X332898D01*
G01X338976Y293224D02*
X333406D01*
G01X347001Y286932D02*
X339484Y294449D01*
G01X345872Y286328D02*
X338976Y293224D01*
G01X318137Y278729D02*
X308582D01*
G01X317629Y279954D02*
X308582D01*
G01X320831Y281423D02*
X318137Y278729D01*
G01X320323Y282648D02*
X317629Y279954D01*
G01X324100Y281423D02*
X320831D01*
G01X324608Y282648D02*
X320323D01*
G01X329251Y276272D02*
X324100Y281423D01*
G01X329759Y277497D02*
X324608Y282648D01*
G01X335748Y276272D02*
X329251D01*
G01X336256Y277497D02*
X329759D01*
G01X342611Y269409D02*
X335748Y276272D01*
G01X343722Y270031D02*
X336256Y277497D01*
G01X317629Y279954D02*
X308582D01*
G01X318137Y278729D02*
X308582D01*
G01X320323Y282648D02*
X317629Y279954D01*
G01X320831Y281423D02*
X318137Y278729D01*
G01X324608Y282648D02*
X320323D01*
G01X324100Y281423D02*
X320831D01*
G01X329759Y277497D02*
X324608Y282648D01*
G01X329251Y276272D02*
X324100Y281423D01*
G01X336256Y277497D02*
X329759D01*
G01X335748Y276272D02*
X329251D01*
G01X343722Y270031D02*
X336256Y277497D01*
G01X342611Y269409D02*
X335748Y276272D01*
G01X332257Y266874D02*
X336395D01*
G01X335887Y265649D02*
X332765D01*
G01X302519Y266185D02*
X301944Y265610D01*
G01X300719Y266118D02*
X302011Y267410D01*
G01X303094Y266185D02*
X302519D01*
G01X302011Y267410D02*
X303093D01*
G01X302011D02*
X303093D01*
G01X303094Y266185D02*
X302519D01*
G01X300719Y266118D02*
X302011Y267410D01*
G01X302519Y266185D02*
X301944Y265610D01*
G01X335887Y265649D02*
X332765D01*
G01X332257Y266874D02*
X336395D01*
G01X317194Y366929D02*
X305182D01*
G01X317702Y368154D02*
X305182D01*
G01X320931Y363192D02*
X317194Y366929D01*
G01X321439Y364417D02*
X317702Y368154D01*
G01X328272Y363192D02*
X320931D01*
G01X327764Y364417D02*
X321439D01*
G01X333842Y368762D02*
X328272Y363192D01*
G01X333334Y369987D02*
X327764Y364417D01*
G01X335595Y368762D02*
X333842D01*
G01X333334Y369987D02*
X327764Y364417D01*
G01X336103Y369987D02*
X333334D01*
G01X348618Y355739D02*
X335595Y368762D01*
G01X349730Y356360D02*
X336103Y369987D01*
G01X317702Y368154D02*
X305182D01*
G01X317194Y366929D02*
X305182D01*
G01X321439Y364417D02*
X317702Y368154D01*
G01X320931Y363192D02*
X317194Y366929D01*
G01X327764Y364417D02*
X321439D01*
G01X328272Y363192D02*
X320931D01*
G01X333334Y369987D02*
X327764Y364417D01*
G01X333842Y368762D02*
X328272Y363192D01*
G01X335595Y368762D02*
X333842D01*
G01X336103Y369987D02*
X333334D01*
G01X335595Y368762D02*
X333842D01*
G01X349730Y356360D02*
X336103Y369987D01*
G01X348618Y355739D02*
X335595Y368762D01*
G01X318237Y354329D02*
X308704D01*
G01X317729Y355554D02*
X308705D01*
G01X320649Y356741D02*
X318237Y354329D01*
G01X320141Y357966D02*
X317729Y355554D01*
G01X328382Y356741D02*
X320649D01*
G01X328890Y357966D02*
X320141D01*
G01X334349Y350774D02*
X328382Y356741D01*
G01X334857Y351999D02*
X328890Y357966D01*
G01X339493Y350774D02*
X334349D01*
G01X340001Y351999D02*
X334857D01*
G01X343268Y346999D02*
X339493Y350774D01*
G01X344221Y347779D02*
X340001Y351999D01*
G01X317729Y355554D02*
X308705D01*
G01X318237Y354329D02*
X308704D01*
G01X320141Y357966D02*
X317729Y355554D01*
G01X320649Y356741D02*
X318237Y354329D01*
G01X328890Y357966D02*
X320141D01*
G01X328382Y356741D02*
X320649D01*
G01X334857Y351999D02*
X328890Y357966D01*
G01X334349Y350774D02*
X328382Y356741D01*
G01X340001Y351999D02*
X334857D01*
G01X339493Y350774D02*
X334349D01*
G01X344221Y347779D02*
X340001Y351999D01*
G01X343268Y346999D02*
X339493Y350774D01*
G01X317194Y341729D02*
X305404D01*
G01X317702Y342954D02*
X305405D01*
G01X320073Y338850D02*
X317194Y341729D01*
G01X320581Y340075D02*
X317702Y342954D01*
G01X329007Y338850D02*
X320073D01*
G01X328499Y340075D02*
X320581D01*
G01X334131Y343974D02*
X329007Y338850D01*
G01X333623Y345199D02*
X328499Y340075D01*
G01X337626Y343974D02*
X334131D01*
G01X338134Y345199D02*
X333623D01*
G01X343040Y338560D02*
X337626Y343974D01*
G01X343990Y339343D02*
X338134Y345199D01*
G01X317702Y342954D02*
X305405D01*
G01X317194Y341729D02*
X305404D01*
G01X320581Y340075D02*
X317702Y342954D01*
G01X320073Y338850D02*
X317194Y341729D01*
G01X328499Y340075D02*
X320581D01*
G01X329007Y338850D02*
X320073D01*
G01X333623Y345199D02*
X328499Y340075D01*
G01X334131Y343974D02*
X329007Y338850D01*
G01X338134Y345199D02*
X333623D01*
G01X337626Y343974D02*
X334131D01*
G01X343990Y339343D02*
X338134Y345199D01*
G01X343040Y338560D02*
X337626Y343974D01*
G01X321355Y332647D02*
X319433Y330723D01*
G01X320847Y333872D02*
X318566Y331590D01*
G01X327533Y332647D02*
X321355D01*
G01X328041Y333872D02*
X320847D01*
G01D02*
X318566Y331590D01*
G01X321355Y332647D02*
X319433Y330723D01*
G01X328041Y333872D02*
X320847D01*
G01X327533Y332647D02*
X321355D01*
G01X417738Y122377D02*
X392353Y139247D01*
G01X418215Y123532D02*
X393234Y140134D01*
G01X418215Y123532D02*
X393234Y140134D01*
G01X417738Y122377D02*
X392353Y139247D01*
G01X417203Y117261D02*
X388660Y136186D01*
G01X417573Y118486D02*
X389540Y137073D01*
G01X417573Y118486D02*
X389540Y137073D01*
G01X417203Y117261D02*
X388660Y136186D01*
G01X384344Y133317D02*
X376751Y144717D01*
G01X415177Y112761D02*
X384344Y133317D01*
G01X415548Y113986D02*
X385228Y134200D01*
G01X384344Y133317D02*
X376751Y144717D01*
G01X415548Y113986D02*
X385228Y134200D01*
G01X415177Y112761D02*
X384344Y133317D01*
G01X380992Y130959D02*
X370320Y146892D01*
G01X379974Y130277D02*
X374638Y138244D01*
G01X380992Y130959D02*
X370320Y146892D01*
G01X380109Y130074D02*
X379973Y130277D01*
G01X380992Y130959D02*
X370320Y146892D01*
G01X412786Y108261D02*
X380109Y130074D01*
G01X413158Y109486D02*
X380992Y130959D01*
G01D02*
X370320Y146892D01*
G01X379974Y130277D02*
X374638Y138244D01*
G01X380109Y130074D02*
X379973Y130277D01*
G01X413158Y109486D02*
X380992Y130959D01*
G01X412786Y108261D02*
X380109Y130074D01*
G01X378202Y123400D02*
X365324Y142626D01*
G01X379087Y124282D02*
X366478Y143106D01*
G01X407317Y103761D02*
X378202Y123400D01*
G01X407692Y104986D02*
X379087Y124282D01*
G01D02*
X366478Y143106D01*
G01X378202Y123400D02*
X365324Y142626D01*
G01X407692Y104986D02*
X379087Y124282D01*
G01X407317Y103761D02*
X378202Y123400D01*
G01X364757Y131114D02*
X362102Y135096D01*
G01X373341Y120447D02*
X363256Y135574D01*
G01X367278Y127332D02*
X364757Y131114D01*
G01X373341Y120447D02*
X363256Y135574D01*
G01X372457Y119563D02*
X367278Y127332D01*
G01X373341Y120447D02*
X363256Y135574D01*
G01X405224Y97710D02*
X372457Y119563D01*
G01X405596Y98935D02*
X373341Y120447D01*
G01X439980Y97710D02*
X405224D01*
G01X439472Y98935D02*
X405596D01*
G01X373341Y120447D02*
X363256Y135574D01*
G01X364757Y131114D02*
X362102Y135096D01*
G01X367278Y127332D02*
X364757Y131114D01*
G01X372457Y119563D02*
X367278Y127332D01*
G01X405596Y98935D02*
X373341Y120447D01*
G01X405224Y97710D02*
X372457Y119563D01*
G01X439472Y98935D02*
X405596D01*
G01X439980Y97710D02*
X405224D01*
G01X358066Y131034D02*
X349615Y173373D01*
G01X359318Y131022D02*
X350865Y173373D01*
G01X357252Y127320D02*
X358066Y131034D01*
G01X358504Y127310D02*
X359318Y131022D01*
G01X357397Y126601D02*
X357252Y127320D01*
G01X358588Y126894D02*
X358504Y127310D01*
G01X359294Y120095D02*
X357397Y126601D01*
G01X360345Y120867D02*
X358588Y126894D01*
G01X400049Y92921D02*
X359294Y120095D01*
G01X400420Y94146D02*
X360345Y120867D01*
G01X449001Y92921D02*
X400049D01*
G01X448493Y94146D02*
X400420D01*
G01X359318Y131022D02*
X350865Y173373D01*
G01X358066Y131034D02*
X349615Y173373D01*
G01X358504Y127310D02*
X359318Y131022D01*
G01X357252Y127320D02*
X358066Y131034D01*
G01X358588Y126894D02*
X358504Y127310D01*
G01X357397Y126601D02*
X357252Y127320D01*
G01X360345Y120867D02*
X358588Y126894D01*
G01X359294Y120095D02*
X357397Y126601D01*
G01X400420Y94146D02*
X360345Y120867D01*
G01X400049Y92921D02*
X359294Y120095D01*
G01X448493Y94146D02*
X400420D01*
G01X449001Y92921D02*
X400049D01*
G01X452571Y87142D02*
X399518D01*
G01X452571D02*
X399518D01*
G01X452571D02*
X399518D01*
G01X452571D02*
X399518D01*
G01X399889Y88367D02*
X403023D01*
G01X452571Y87142D02*
X399518D01*
G01X355843Y117737D02*
X399889Y88367D01*
G01X399518Y87142D02*
X354786Y116968D01*
G01X353035Y127702D02*
X355843Y117737D01*
G01X354786Y116968D02*
X351776Y127650D01*
G01X353725Y131252D02*
X353035Y127702D01*
G01X351776Y127650D02*
X352477Y131252D01*
G01X342811Y187410D02*
X353725Y131252D01*
G01X352477D02*
X341562Y187411D01*
G01X352477Y131252D02*
X341562Y187411D01*
G01X342811Y187410D02*
X353725Y131252D01*
G01X351776Y127650D02*
X352477Y131252D01*
G01X353725D02*
X353035Y127702D01*
G01X354786Y116968D02*
X351776Y127650D01*
G01X353035Y127702D02*
X355843Y117737D01*
G01X399518Y87142D02*
X354786Y116968D01*
G01X355843Y117737D02*
X399889Y88367D01*
G01X452571Y87142D02*
X399518D01*
G01X399889Y88367D02*
X403023D01*
G01X397597Y160737D02*
X399036D01*
G01X397089Y159512D02*
X398902D01*
G01X396821Y161513D02*
X397597Y160737D01*
G01X395596Y161005D02*
X397089Y159512D01*
G01X396821Y166270D02*
Y161513D01*
G01X395596Y166778D02*
Y161005D01*
G01X398900Y168349D02*
X396821Y166270D01*
G01X397675Y168857D02*
X395596Y166778D01*
G01X398900Y303735D02*
Y168349D01*
G01X397675Y303227D02*
Y168857D01*
G01X397597Y160737D02*
X399036D01*
G01X397089Y159512D02*
X398902D01*
G01X396821Y161513D02*
X397597Y160737D01*
G01X395596Y161005D02*
X397089Y159512D01*
G01X396821Y166270D02*
Y161513D01*
G01X395596Y166778D02*
Y161005D01*
G01X398900Y168349D02*
X396821Y166270D01*
G01X397675Y168857D02*
X395596Y166778D01*
G01X398900Y303735D02*
Y168349D01*
G01X397675Y303227D02*
Y168857D01*
G01X397089Y159512D02*
X398902D01*
G01X397597Y160737D02*
X399036D01*
G01X395596Y161005D02*
X397089Y159512D01*
G01X396821Y161513D02*
X397597Y160737D01*
G01X395596Y166778D02*
Y161005D01*
G01X396821Y166270D02*
Y161513D01*
G01X397675Y168857D02*
X395596Y166778D01*
G01X398900Y168349D02*
X396821Y166270D01*
G01X397675Y303227D02*
Y168857D01*
G01X398900Y303735D02*
Y168349D01*
G01X397089Y159512D02*
X398902D01*
G01X397597Y160737D02*
X399036D01*
G01X395596Y161005D02*
X397089Y159512D01*
G01X396821Y161513D02*
X397597Y160737D01*
G01X395596Y166778D02*
Y161005D01*
G01X396821Y166270D02*
Y161513D01*
G01X397675Y168857D02*
X395596Y166778D01*
G01X398900Y168349D02*
X396821Y166270D01*
G01X397675Y303227D02*
Y168857D01*
G01X398900Y303735D02*
Y168349D01*
G01X397597Y160737D02*
X399036D01*
G01X397089Y159512D02*
X398902D01*
G01X396821Y161513D02*
X397597Y160737D01*
G01X395596Y161005D02*
X397089Y159512D01*
G01X396821Y166270D02*
Y161513D01*
G01X395596Y166778D02*
Y161005D01*
G01X398900Y168349D02*
X396821Y166270D01*
G01X397675Y168857D02*
X395596Y166778D01*
G01X398900Y303735D02*
Y168349D01*
G01X397675Y303227D02*
Y168857D01*
G01X397089Y159512D02*
X398902D01*
G01X397597Y160737D02*
X399036D01*
G01X395596Y161005D02*
X397089Y159512D01*
G01X396821Y161513D02*
X397597Y160737D01*
G01X395596Y166778D02*
Y161005D01*
G01X396821Y166270D02*
Y161513D01*
G01X397675Y168857D02*
X395596Y166778D01*
G01X398900Y168349D02*
X396821Y166270D01*
G01X397675Y303227D02*
Y168857D01*
G01X398900Y303735D02*
Y168349D01*
G01X387194Y176875D02*
X392389Y202856D01*
G01X388444Y176875D02*
X393639Y202856D01*
G01X387993Y172870D02*
X387194Y176875D01*
G01X388819Y174995D02*
X388444Y176875D01*
G01X388913Y174524D02*
X388819Y174995D01*
G01X388369Y170987D02*
X387993Y172870D01*
G01X389947Y169344D02*
X388913Y174524D01*
G01X393304Y146262D02*
X388369Y170987D01*
G01X391450Y161810D02*
X389948Y169343D01*
G01X394458Y146742D02*
X391450Y161810D01*
G01X394602Y144326D02*
X393304Y146262D01*
G01X395485Y145211D02*
X394458Y146742D01*
G01X410151Y133961D02*
X394602Y144326D01*
G01X410629Y135115D02*
X395485Y145211D01*
G01X388444Y176875D02*
X393639Y202856D01*
G01X387194Y176875D02*
X392389Y202856D01*
G01X388819Y174995D02*
X388444Y176875D01*
G01X387993Y172870D02*
X387194Y176875D01*
G01X388913Y174524D02*
X388819Y174995D01*
G01X387993Y172870D02*
X387194Y176875D01*
G01X389947Y169344D02*
X388913Y174524D01*
G01X388369Y170987D02*
X387993Y172870D01*
G01X391450Y161810D02*
X389948Y169343D01*
G01X393304Y146262D02*
X388369Y170987D01*
G01X394458Y146742D02*
X391450Y161810D01*
G01X393304Y146262D02*
X388369Y170987D01*
G01X395485Y145211D02*
X394458Y146742D01*
G01X394602Y144326D02*
X393304Y146262D01*
G01X410629Y135115D02*
X395485Y145211D01*
G01X410151Y133961D02*
X394602Y144326D01*
G01X380500Y174332D02*
X386792Y205720D01*
G01X384848Y189785D02*
X388042Y205720D01*
G01X381750Y174328D02*
X384848Y189785D01*
G01X385288Y149718D02*
X380500Y174332D01*
G01X386443Y150197D02*
X381750Y174328D01*
G01X392353Y139247D02*
X385288Y149718D01*
G01X393234Y140134D02*
X386443Y150197D01*
G01X384848Y189785D02*
X388042Y205720D01*
G01X380500Y174332D02*
X386792Y205720D01*
G01X381750Y174328D02*
X384848Y189785D01*
G01X380500Y174332D02*
X386792Y205720D01*
G01X386443Y150197D02*
X381750Y174328D01*
G01X385288Y149718D02*
X380500Y174332D01*
G01X393234Y140134D02*
X386443Y150197D01*
G01X392353Y139247D02*
X385288Y149718D01*
G01X375706Y173811D02*
X381331Y201925D01*
G01X376956Y173811D02*
X382581Y201925D01*
G01X380939Y147632D02*
X375706Y173811D01*
G01X382093Y148114D02*
X376956Y173811D01*
G01X388660Y136186D02*
X380939Y147632D01*
G01X389540Y137073D02*
X382093Y148114D01*
G01X376956Y173811D02*
X382581Y201925D01*
G01X375706Y173811D02*
X381331Y201925D01*
G01X382093Y148114D02*
X376956Y173811D01*
G01X380939Y147632D02*
X375706Y173811D01*
G01X389540Y137073D02*
X382093Y148114D01*
G01X388660Y136186D02*
X380939Y147632D01*
G01X370987Y173490D02*
X376688Y201951D01*
G01X372237Y173490D02*
X377938Y201951D01*
G01X376751Y144717D02*
X370987Y173490D01*
G01X377905Y145195D02*
X372237Y173490D01*
G01X385228Y134200D02*
X377905Y145195D01*
G01X372237Y173490D02*
X377938Y201951D01*
G01X370987Y173490D02*
X376688Y201951D01*
G01X377905Y145195D02*
X372237Y173490D01*
G01X376751Y144717D02*
X370987Y173490D01*
G01X385228Y134200D02*
X377905Y145195D01*
G01X369046Y196122D02*
X367392Y204377D01*
G01X370296Y196122D02*
X368642Y204378D01*
G01X366613Y183965D02*
X369046Y196122D01*
G01X365382Y171566D02*
X370296Y196122D01*
G01X364180Y171806D02*
X366613Y183965D01*
G01X365382Y171566D02*
X370296Y196122D01*
G01X364132Y171566D02*
X364180Y171806D01*
G01X365382Y171566D02*
X370296Y196122D01*
G01X369166Y146412D02*
X364132Y171566D01*
G01X370320Y146892D02*
X365382Y171566D01*
G01X374638Y138244D02*
X369166Y146412D01*
G01X370296Y196122D02*
X368642Y204378D01*
G01X369046Y196122D02*
X367392Y204377D01*
G01X365382Y171566D02*
X370296Y196122D01*
G01X366613Y183965D02*
X369046Y196122D01*
G01X364180Y171806D02*
X366613Y183965D01*
G01X364132Y171566D02*
X364180Y171806D01*
G01X370320Y146892D02*
X365382Y171566D01*
G01X369166Y146412D02*
X364132Y171566D01*
G01X374638Y138244D02*
X369166Y146412D01*
G01X363954Y195177D02*
X362346Y202727D01*
G01X365207Y195177D02*
X363599Y202727D01*
G01X362777Y189635D02*
X363954Y195177D01*
G01X364565Y192151D02*
X365207Y195177D01*
G01X361598Y184090D02*
X362776Y189634D01*
G01X360495Y172997D02*
X364565Y192151D01*
G01X359296Y173251D02*
X361598Y184090D01*
G01X360495Y172997D02*
X364565Y192151D01*
G01X359244Y173004D02*
X359296Y173251D01*
G01X360495Y172997D02*
X364565Y192151D01*
G01X365324Y142626D02*
X359244Y173004D01*
G01X366478Y143106D02*
X360495Y172997D01*
G01X365207Y195177D02*
X363599Y202727D01*
G01X363954Y195177D02*
X362346Y202727D01*
G01X364565Y192151D02*
X365207Y195177D01*
G01X362777Y189635D02*
X363954Y195177D01*
G01X360495Y172997D02*
X364565Y192151D01*
G01X361598Y184090D02*
X362776Y189634D01*
G01X359296Y173251D02*
X361598Y184090D01*
G01X359244Y173004D02*
X359296Y173251D01*
G01X366478Y143106D02*
X360495Y172997D01*
G01X365324Y142626D02*
X359244Y173004D01*
G01X356697Y190361D02*
X354885Y199557D01*
G01X358535Y187374D02*
X356134Y199555D01*
G01X357285Y187376D02*
X356696Y190361D01*
G01X358535Y187374D02*
X356134Y199555D01*
G01X355928Y180582D02*
X357286Y187376D01*
G01X357532Y182351D02*
X358535Y187374D01*
G01X354522Y173550D02*
X355928Y180582D01*
G01X355724Y173310D02*
X357532Y182351D01*
G01X354474Y173310D02*
X354521Y173550D01*
G01X355724Y173310D02*
X357532Y182351D01*
G01X362102Y135096D02*
X354474Y173310D01*
G01X363256Y135574D02*
X355724Y173310D01*
G01X358535Y187374D02*
X356134Y199555D01*
G01X356697Y190361D02*
X354885Y199557D01*
G01X357285Y187376D02*
X356696Y190361D01*
G01X357532Y182351D02*
X358535Y187374D01*
G01X355928Y180582D02*
X357286Y187376D01*
G01X355724Y173310D02*
X357532Y182351D01*
G01X354522Y173550D02*
X355928Y180582D01*
G01X354474Y173310D02*
X354521Y173550D01*
G01X363256Y135574D02*
X355724Y173310D01*
G01X362102Y135096D02*
X354474Y173310D01*
G01X350736Y196709D02*
X350121Y199849D01*
G01X351939Y196944D02*
X351370Y199850D01*
G01X350852Y196112D02*
X350736Y196709D01*
G01X351939Y196944D02*
X351370Y199850D01*
G01X352173Y195750D02*
X351939Y196944D01*
G01X350926Y195739D02*
X350852Y196112D01*
G01X352173Y195750D02*
X351939Y196944D01*
G01X350970Y195515D02*
X350926Y195739D01*
G01X352173Y195750D02*
X351939Y196944D01*
G01X352509Y194036D02*
X352173Y195750D01*
G01X352491Y187751D02*
X350970Y195515D01*
G01X352509Y194036D02*
X352173Y195750D01*
G01X353740Y187748D02*
X352509Y194036D01*
G01X349615Y173373D02*
X352491Y187751D01*
G01X350865Y173373D02*
X353740Y187748D01*
G01X351939Y196944D02*
X351370Y199850D01*
G01X350736Y196709D02*
X350121Y199849D01*
G01X350852Y196112D02*
X350736Y196709D01*
G01X352173Y195750D02*
X351939Y196944D01*
G01X350852Y196112D02*
X350736Y196709D01*
G01X350926Y195739D02*
X350852Y196112D01*
G01X350970Y195515D02*
X350926Y195739D01*
G01X352509Y194036D02*
X352173Y195750D01*
G01X350970Y195515D02*
X350926Y195739D01*
G01X352491Y187751D02*
X350970Y195515D01*
G01X353740Y187748D02*
X352509Y194036D01*
G01X352491Y187751D02*
X350970Y195515D01*
G01X350865Y173373D02*
X353740Y187748D01*
G01X349615Y173373D02*
X352491Y187751D01*
G01X344036Y193667D02*
X342811Y187410D01*
G01X341563Y187413D02*
X345519Y207631D01*
G01X344929Y198231D02*
X344598Y196538D01*
G01X341563Y187413D02*
X345519Y207631D01*
G01X341563Y187413D02*
X345519Y207631D01*
G01X341563Y187413D02*
X345519Y207631D01*
G01X344036Y193667D02*
X342811Y187410D01*
G01X344929Y198231D02*
X344598Y196538D01*
G01X392389Y202856D02*
X369916Y315225D01*
G01X393639Y202856D02*
X371070Y315703D01*
G01X393639Y202856D02*
X371070Y315703D01*
G01X392389Y202856D02*
X369916Y315225D01*
G01X386792Y205720D02*
X365077Y314284D01*
G01X388042Y205720D02*
X366231Y314762D01*
G01X388042Y205720D02*
X366231Y314762D01*
G01X386792Y205720D02*
X365077Y314284D01*
G01X381331Y201925D02*
X358582Y315672D01*
G01X382581Y201925D02*
X359735Y316155D01*
G01X382581Y201925D02*
X359735Y316155D01*
G01X381331Y201925D02*
X358582Y315672D01*
G01X376688Y201951D02*
X354618Y312282D01*
G01X377938Y201951D02*
X355747Y312886D01*
G01X377938Y201951D02*
X355747Y312886D01*
G01X376688Y201951D02*
X354618Y312282D01*
G01X369478Y214862D02*
X350709Y308691D01*
G01X370728Y214863D02*
X351838Y309295D01*
G01X367392Y204377D02*
X369478Y214862D01*
G01X368642Y204378D02*
X370728Y214863D01*
G01D02*
X351838Y309295D01*
G01X369478Y214862D02*
X350709Y308691D01*
G01X368642Y204378D02*
X370728Y214863D01*
G01X367392Y204377D02*
X369478Y214862D01*
G01X357314Y252202D02*
X348666Y295434D01*
G01X358573Y252156D02*
X349795Y296038D01*
G01X356470Y249159D02*
X357314Y252202D01*
G01X358073Y250354D02*
X358573Y252156D01*
G01X357651Y248831D02*
X358073Y250354D01*
G01X355902Y247111D02*
X356470Y249159D01*
G01X357083Y246783D02*
X357651Y248831D01*
G01X354616Y242477D02*
X355902Y247111D01*
G01X355877Y242438D02*
X357083Y246783D01*
G01X362698Y204380D02*
X354616Y242477D01*
G01X363951Y204380D02*
X355877Y242438D01*
G01X362346Y202727D02*
X362698Y204380D01*
G01X363599Y202727D02*
X363951Y204380D01*
G01X358573Y252156D02*
X349795Y296038D01*
G01X357314Y252202D02*
X348666Y295434D01*
G01X358073Y250354D02*
X358573Y252156D01*
G01X356470Y249159D02*
X357314Y252202D01*
G01X357651Y248831D02*
X358073Y250354D01*
G01X356470Y249159D02*
X357314Y252202D01*
G01X357083Y246783D02*
X357651Y248831D01*
G01X355902Y247111D02*
X356470Y249159D01*
G01X355877Y242438D02*
X357083Y246783D01*
G01X354616Y242477D02*
X355902Y247111D01*
G01X363951Y204380D02*
X355877Y242438D01*
G01X362698Y204380D02*
X354616Y242477D01*
G01X363599Y202727D02*
X363951Y204380D01*
G01X362346Y202727D02*
X362698Y204380D01*
G01X350561Y262881D02*
X345872Y286328D01*
G01X352126Y255064D02*
X350562Y262881D01*
G01X353385Y255018D02*
X350201Y270936D01*
G01X349203Y244528D02*
X352126Y255064D01*
G01X350462Y244482D02*
X353385Y255018D01*
G01X356545Y207856D02*
X349203Y244528D01*
G01X357795Y207856D02*
X350462Y244482D01*
G01X354885Y199557D02*
X356545Y207856D01*
G01X356134Y199555D02*
X357795Y207856D01*
G01X350561Y262881D02*
X345872Y286328D01*
G01X353385Y255018D02*
X350201Y270936D01*
G01X352126Y255064D02*
X350562Y262881D01*
G01X350462Y244482D02*
X353385Y255018D01*
G01X349203Y244528D02*
X352126Y255064D01*
G01X357795Y207856D02*
X350462Y244482D01*
G01X356545Y207856D02*
X349203Y244528D01*
G01X356134Y199555D02*
X357795Y207856D01*
G01X354885Y199557D02*
X356545Y207856D01*
G01X344867Y259988D02*
X342611Y269409D01*
G01X346115Y260039D02*
X343722Y270031D01*
G01X343959Y254098D02*
X344867Y259988D01*
G01X345203Y254122D02*
X346115Y260039D01*
G01X344148Y253110D02*
X343960Y254098D01*
G01X345501Y252557D02*
X345203Y254121D01*
G01X344297Y252328D02*
X344148Y253110D01*
G01X345501Y252557D02*
X345203Y254121D01*
G01X345838Y250784D02*
X345501Y252557D01*
G01X344314Y252233D02*
X344297Y252328D01*
G01X345501Y252557D02*
X345203Y254121D01*
G01X345838Y250784D02*
X345501Y252557D01*
G01X344595Y250762D02*
X344315Y252233D01*
G01X345838Y250784D02*
X345501Y252557D01*
G01X343899Y246246D02*
X344595Y250762D01*
G01X345142Y246268D02*
X345838Y250784D01*
G01X351438Y206621D02*
X343899Y246246D01*
G01X352686Y206619D02*
X345142Y246268D01*
G01X350121Y199849D02*
X351438Y206621D01*
G01X351370Y199850D02*
X352686Y206619D01*
G01X346115Y260039D02*
X343722Y270031D01*
G01X344867Y259988D02*
X342611Y269409D01*
G01X345203Y254122D02*
X346115Y260039D01*
G01X343959Y254098D02*
X344867Y259988D01*
G01X345501Y252557D02*
X345203Y254121D01*
G01X344148Y253110D02*
X343960Y254098D01*
G01X344297Y252328D02*
X344148Y253110D01*
G01X344314Y252233D02*
X344297Y252328D01*
G01X345838Y250784D02*
X345501Y252557D01*
G01X344297Y252328D02*
X344148Y253110D01*
G01X344314Y252233D02*
X344297Y252328D01*
G01X344595Y250762D02*
X344315Y252233D01*
G01X345142Y246268D02*
X345838Y250784D01*
G01X343899Y246246D02*
X344595Y250762D01*
G01X352686Y206619D02*
X345142Y246268D01*
G01X351438Y206621D02*
X343899Y246246D01*
G01X351370Y199850D02*
X352686Y206619D01*
G01X350121Y199849D02*
X351438Y206621D01*
G01X346768Y207630D02*
X345491Y201101D01*
G01X342537Y229399D02*
X346768Y207630D01*
G01X341650Y233963D02*
X341979Y232270D01*
G01X340762Y238528D02*
X341091Y236835D01*
G01X342537Y229399D02*
X346768Y207630D01*
G01X341650Y233963D02*
X341979Y232270D01*
G01X340762Y238528D02*
X341091Y236835D01*
G01X346768Y207630D02*
X345491Y201101D01*
G01X384787Y317848D02*
X398900Y303735D01*
G01X357663Y343239D02*
X397675Y303227D01*
G01X381498Y321137D02*
X382718Y319917D01*
G01X357663Y343239D02*
X397675Y303227D01*
G01X378210Y324425D02*
X379430Y323205D01*
G01X357663Y343239D02*
X397675Y303227D01*
G01X374922Y327713D02*
X376142Y326493D01*
G01X357663Y343239D02*
X397675Y303227D01*
G01X358888Y343747D02*
X372854Y329781D01*
G01X357663Y343239D02*
X397675Y303227D01*
G01X384787Y317848D02*
X398900Y303735D01*
G01X357663Y343239D02*
X397675Y303227D01*
G01X381498Y321137D02*
X382718Y319917D01*
G01X357663Y343239D02*
X397675Y303227D01*
G01X378210Y324425D02*
X379430Y323205D01*
G01X357663Y343239D02*
X397675Y303227D01*
G01X374922Y327713D02*
X376142Y326493D01*
G01X357663Y343239D02*
X397675Y303227D01*
G01X358888Y343747D02*
X372854Y329781D01*
G01X357663Y343239D02*
X397675Y303227D01*
G01X357663Y343239D02*
X397675Y303227D01*
G01X384787Y317848D02*
X398900Y303735D01*
G01X381498Y321137D02*
X382718Y319917D01*
G01X378210Y324425D02*
X379430Y323205D01*
G01X374922Y327713D02*
X376142Y326493D01*
G01X358888Y343747D02*
X372854Y329781D01*
G01X357663Y343239D02*
X397675Y303227D01*
G01X384787Y317848D02*
X398900Y303735D01*
G01X381498Y321137D02*
X382718Y319917D01*
G01X378210Y324425D02*
X379430Y323205D01*
G01X374922Y327713D02*
X376142Y326493D01*
G01X358888Y343747D02*
X372854Y329781D01*
G01X384787Y317848D02*
X398900Y303735D01*
G01X357663Y343239D02*
X397675Y303227D01*
G01X381498Y321137D02*
X382718Y319917D01*
G01X357663Y343239D02*
X397675Y303227D01*
G01X378210Y324425D02*
X379430Y323205D01*
G01X357663Y343239D02*
X397675Y303227D01*
G01X374922Y327713D02*
X376142Y326493D01*
G01X357663Y343239D02*
X397675Y303227D01*
G01X358888Y343747D02*
X372854Y329781D01*
G01X357663Y343239D02*
X397675Y303227D01*
G01X357663Y343239D02*
X397675Y303227D01*
G01X384787Y317848D02*
X398900Y303735D01*
G01X381498Y321137D02*
X382718Y319917D01*
G01X378210Y324425D02*
X379430Y323205D01*
G01X374922Y327713D02*
X376142Y326493D01*
G01X358888Y343747D02*
X372854Y329781D01*
G01X369916Y315225D02*
X351767Y342453D01*
G01X371070Y315703D02*
X352909Y342950D01*
G01X371070Y315703D02*
X352909Y342950D01*
G01X369916Y315225D02*
X351767Y342453D01*
G01X365077Y314284D02*
X343268Y346999D01*
G01X366231Y314762D02*
X344221Y347779D01*
G01X366231Y314762D02*
X344221Y347779D01*
G01X365077Y314284D02*
X343268Y346999D01*
G01X358582Y315672D02*
X343040Y338560D01*
G01X359735Y316155D02*
X343990Y339343D01*
G01X359735Y316155D02*
X343990Y339343D01*
G01X358582Y315672D02*
X343040Y338560D01*
G01X355747Y312886D02*
X340881Y327752D01*
G01X355747Y312886D02*
X340881Y327752D01*
G01X350709Y308691D02*
X341006Y318394D01*
G01X351838Y309295D02*
X341514Y319619D01*
G01X351838Y309295D02*
X341514Y319619D01*
G01X350709Y308691D02*
X341006Y318394D01*
G01X348666Y295434D02*
X342163Y301937D01*
G01X349795Y296038D02*
X342671Y303162D01*
G01X349795Y296038D02*
X342671Y303162D01*
G01X348666Y295434D02*
X342163Y301937D01*
G01X350201Y270936D02*
X347001Y286932D01*
G01X350201Y270936D02*
X347001Y286932D01*
G01X358888Y347916D02*
Y343747D01*
G01X357663Y348424D02*
Y343239D01*
G01X368204Y357232D02*
X358888Y347916D01*
G01X367696Y358457D02*
X357663Y348424D01*
G01X378575Y357232D02*
X368204D01*
G01X378067Y358457D02*
X367696D01*
G01X387958Y366615D02*
X378575Y357232D01*
G01X386733Y367123D02*
X378067Y358457D01*
G01X387958Y436223D02*
Y366615D01*
G01X386733Y424903D02*
Y367123D01*
G01X358888Y347916D02*
Y343747D01*
G01X357663Y348424D02*
Y343239D01*
G01X368204Y357232D02*
X358888Y347916D01*
G01X367696Y358457D02*
X357663Y348424D01*
G01X378575Y357232D02*
X368204D01*
G01X378067Y358457D02*
X367696D01*
G01X387958Y366615D02*
X378575Y357232D01*
G01X386733Y367123D02*
X378067Y358457D01*
G01X387958Y436223D02*
Y366615D01*
G01X386733Y424903D02*
Y367123D01*
G01X357663Y348424D02*
Y343239D01*
G01X358888Y347916D02*
Y343747D01*
G01X367696Y358457D02*
X357663Y348424D01*
G01X368204Y357232D02*
X358888Y347916D01*
G01X378067Y358457D02*
X367696D01*
G01X378575Y357232D02*
X368204D01*
G01X386733Y367123D02*
X378067Y358457D01*
G01X387958Y366615D02*
X378575Y357232D01*
G01X386733Y424903D02*
Y367123D01*
G01X387958Y436223D02*
Y366615D01*
G01X357663Y348424D02*
Y343239D01*
G01X358888Y347916D02*
Y343747D01*
G01X367696Y358457D02*
X357663Y348424D01*
G01X368204Y357232D02*
X358888Y347916D01*
G01X378067Y358457D02*
X367696D01*
G01X378575Y357232D02*
X368204D01*
G01X386733Y367123D02*
X378067Y358457D01*
G01X387958Y366615D02*
X378575Y357232D01*
G01X386733Y424903D02*
Y367123D01*
G01X387958Y436223D02*
Y366615D01*
G01X358888Y347916D02*
Y343747D01*
G01X357663Y348424D02*
Y343239D01*
G01X368204Y357232D02*
X358888Y347916D01*
G01X367696Y358457D02*
X357663Y348424D01*
G01X378575Y357232D02*
X368204D01*
G01X378067Y358457D02*
X367696D01*
G01X387958Y366615D02*
X378575Y357232D01*
G01X386733Y367123D02*
X378067Y358457D01*
G01X387958Y436223D02*
Y366615D01*
G01X386733Y424903D02*
Y367123D01*
G01X357663Y348424D02*
Y343239D01*
G01X358888Y347916D02*
Y343747D01*
G01X367696Y358457D02*
X357663Y348424D01*
G01X368204Y357232D02*
X358888Y347916D01*
G01X378067Y358457D02*
X367696D01*
G01X378575Y357232D02*
X368204D01*
G01X386733Y367123D02*
X378067Y358457D01*
G01X387958Y366615D02*
X378575Y357232D01*
G01X386733Y424903D02*
Y367123D01*
G01X387958Y436223D02*
Y366615D01*
G01X351767Y342453D02*
X348618Y355739D01*
G01X352909Y342950D02*
X349730Y356360D01*
G01X352909Y342950D02*
X349730Y356360D01*
G01X351767Y342453D02*
X348618Y355739D01*
G01X387958Y450245D02*
Y436223D01*
G01X386733Y449737D02*
Y424903D01*
G01X382603Y455600D02*
X387958Y450245D01*
G01X381378Y455092D02*
X386733Y449737D01*
G01X382603Y483313D02*
Y455600D01*
G01X381378Y483821D02*
Y455092D01*
G01X387958Y450245D02*
Y436223D01*
G01X386733Y449737D02*
Y424903D01*
G01X382603Y455600D02*
X387958Y450245D01*
G01X381378Y455092D02*
X386733Y449737D01*
G01X382603Y483313D02*
Y455600D01*
G01X381378Y483821D02*
Y455092D01*
G01X386733Y449737D02*
Y424903D01*
G01X387958Y450245D02*
Y436223D01*
G01X381378Y455092D02*
X386733Y449737D01*
G01X382603Y455600D02*
X387958Y450245D01*
G01X381378Y483821D02*
Y455092D01*
G01X382603Y483313D02*
Y455600D01*
G01X386733Y449737D02*
Y424903D01*
G01X387958Y450245D02*
Y436223D01*
G01X381378Y455092D02*
X386733Y449737D01*
G01X382603Y455600D02*
X387958Y450245D01*
G01X381378Y483821D02*
Y455092D01*
G01X382603Y483313D02*
Y455600D01*
G01X387958Y450245D02*
Y436223D01*
G01X386733Y449737D02*
Y424903D01*
G01X382603Y455600D02*
X387958Y450245D01*
G01X381378Y455092D02*
X386733Y449737D01*
G01X382603Y483313D02*
Y455600D01*
G01X381378Y483821D02*
Y455092D01*
G01X386733Y449737D02*
Y424903D01*
G01X387958Y450245D02*
Y436223D01*
G01X381378Y455092D02*
X386733Y449737D01*
G01X382603Y455600D02*
X387958Y450245D01*
G01X381378Y483821D02*
Y455092D01*
G01X382603Y483313D02*
Y455600D01*
G01X391645Y492355D02*
X382603Y483313D01*
G01X390420Y492863D02*
X381378Y483821D01*
G01X391645Y504919D02*
Y492355D01*
G01X390420Y505427D02*
Y492863D01*
G01X394100Y507374D02*
X391645Y504919D01*
G01X392875Y507882D02*
X390420Y505427D01*
G01X394100Y549666D02*
Y507374D01*
G01X392875Y549158D02*
Y507882D01*
G01X391645Y492355D02*
X382603Y483313D01*
G01X390420Y492863D02*
X381378Y483821D01*
G01X391645Y504919D02*
Y492355D01*
G01X390420Y505427D02*
Y492863D01*
G01X394100Y507374D02*
X391645Y504919D01*
G01X392875Y507882D02*
X390420Y505427D01*
G01X394100Y549666D02*
Y507374D01*
G01X392875Y549158D02*
Y507882D01*
G01X390420Y492863D02*
X381378Y483821D01*
G01X391645Y492355D02*
X382603Y483313D01*
G01X390420Y505427D02*
Y492863D01*
G01X391645Y504919D02*
Y492355D01*
G01X392875Y507882D02*
X390420Y505427D01*
G01X394100Y507374D02*
X391645Y504919D01*
G01X392875Y549158D02*
Y507882D01*
G01X394100Y549666D02*
Y507374D01*
G01X390420Y492863D02*
X381378Y483821D01*
G01X391645Y492355D02*
X382603Y483313D01*
G01X390420Y505427D02*
Y492863D01*
G01X391645Y504919D02*
Y492355D01*
G01X392875Y507882D02*
X390420Y505427D01*
G01X394100Y507374D02*
X391645Y504919D01*
G01X392875Y549158D02*
Y507882D01*
G01X394100Y549666D02*
Y507374D01*
G01X391645Y492355D02*
X382603Y483313D01*
G01X390420Y492863D02*
X381378Y483821D01*
G01X391645Y504919D02*
Y492355D01*
G01X390420Y505427D02*
Y492863D01*
G01X394100Y507374D02*
X391645Y504919D01*
G01X392875Y507882D02*
X390420Y505427D01*
G01X394100Y549666D02*
Y507374D01*
G01X392875Y549158D02*
Y507882D01*
G01X390420Y492863D02*
X381378Y483821D01*
G01X391645Y492355D02*
X382603Y483313D01*
G01X390420Y505427D02*
Y492863D01*
G01X391645Y504919D02*
Y492355D01*
G01X392875Y507882D02*
X390420Y505427D01*
G01X394100Y507374D02*
X391645Y504919D01*
G01X392875Y549158D02*
Y507882D01*
G01X394100Y549666D02*
Y507374D01*
G01X391612Y552154D02*
X394100Y549666D01*
G01X390387Y551646D02*
X392875Y549158D01*
G01X391612Y578081D02*
Y552154D01*
G01X390387Y577573D02*
Y551646D01*
G01X389671Y580022D02*
X391612Y578081D01*
G01X388446Y579514D02*
X390387Y577573D01*
G01X389671Y609226D02*
Y580022D01*
G01X388446Y608718D02*
Y579514D01*
G01X391612Y552154D02*
X394100Y549666D01*
G01X390387Y551646D02*
X392875Y549158D01*
G01X391612Y578081D02*
Y552154D01*
G01X390387Y577573D02*
Y551646D01*
G01X389671Y580022D02*
X391612Y578081D01*
G01X388446Y579514D02*
X390387Y577573D01*
G01X389671Y609226D02*
Y580022D01*
G01X388446Y608718D02*
Y579514D01*
G01X390387Y551646D02*
X392875Y549158D01*
G01X391612Y552154D02*
X394100Y549666D01*
G01X390387Y577573D02*
Y551646D01*
G01X391612Y578081D02*
Y552154D01*
G01X388446Y579514D02*
X390387Y577573D01*
G01X389671Y580022D02*
X391612Y578081D01*
G01X388446Y608718D02*
Y579514D01*
G01X389671Y609226D02*
Y580022D01*
G01X390387Y551646D02*
X392875Y549158D01*
G01X391612Y552154D02*
X394100Y549666D01*
G01X390387Y577573D02*
Y551646D01*
G01X391612Y578081D02*
Y552154D01*
G01X388446Y579514D02*
X390387Y577573D01*
G01X389671Y580022D02*
X391612Y578081D01*
G01X388446Y608718D02*
Y579514D01*
G01X389671Y609226D02*
Y580022D01*
G01X391612Y552154D02*
X394100Y549666D01*
G01X390387Y551646D02*
X392875Y549158D01*
G01X391612Y578081D02*
Y552154D01*
G01X390387Y577573D02*
Y551646D01*
G01X389671Y580022D02*
X391612Y578081D01*
G01X388446Y579514D02*
X390387Y577573D01*
G01X389671Y609226D02*
Y580022D01*
G01X388446Y608718D02*
Y579514D01*
G01X390387Y551646D02*
X392875Y549158D01*
G01X391612Y552154D02*
X394100Y549666D01*
G01X390387Y577573D02*
Y551646D01*
G01X391612Y578081D02*
Y552154D01*
G01X388446Y579514D02*
X390387Y577573D01*
G01X389671Y580022D02*
X391612Y578081D01*
G01X388446Y608718D02*
Y579514D01*
G01X389671Y609226D02*
Y580022D01*
G01X388217Y610680D02*
X389671Y609226D01*
G01X386992Y610172D02*
X388446Y608718D01*
G01X388217Y617502D02*
Y610680D01*
G01X386992Y618010D02*
Y610172D01*
G01X390975Y620260D02*
X388217Y617502D01*
G01X389750Y620768D02*
X386992Y618010D01*
G01X390975Y641629D02*
Y620260D01*
G01X389750Y641121D02*
Y620768D01*
G01X388137Y644467D02*
X390975Y641629D01*
G01X387629Y643242D02*
X389750Y641121D01*
G01X383440Y644467D02*
X388137D01*
G01X383948Y643242D02*
X387629D01*
G01X381775Y642802D02*
X383440Y644467D01*
G01X383000Y642294D02*
X383948Y643242D01*
G01X381775Y639437D02*
Y642802D01*
G01X383000Y639263D02*
Y642294D01*
G01X388217Y610680D02*
X389671Y609226D01*
G01X386992Y610172D02*
X388446Y608718D01*
G01X388217Y617502D02*
Y610680D01*
G01X386992Y618010D02*
Y610172D01*
G01X390975Y620260D02*
X388217Y617502D01*
G01X389750Y620768D02*
X386992Y618010D01*
G01X390975Y641629D02*
Y620260D01*
G01X389750Y641121D02*
Y620768D01*
G01X388137Y644467D02*
X390975Y641629D01*
G01X387629Y643242D02*
X389750Y641121D01*
G01X383440Y644467D02*
X388137D01*
G01X383948Y643242D02*
X387629D01*
G01X381775Y642802D02*
X383440Y644467D01*
G01X383000Y642294D02*
X383948Y643242D01*
G01X381775Y639437D02*
Y642802D01*
G01X383000Y639263D02*
Y642294D01*
G01X386992Y610172D02*
X388446Y608718D01*
G01X388217Y610680D02*
X389671Y609226D01*
G01X386992Y618010D02*
Y610172D01*
G01X388217Y617502D02*
Y610680D01*
G01X389750Y620768D02*
X386992Y618010D01*
G01X390975Y620260D02*
X388217Y617502D01*
G01X389750Y641121D02*
Y620768D01*
G01X390975Y641629D02*
Y620260D01*
G01X387629Y643242D02*
X389750Y641121D01*
G01X388137Y644467D02*
X390975Y641629D01*
G01X383948Y643242D02*
X387629D01*
G01X383440Y644467D02*
X388137D01*
G01X383000Y642294D02*
X383948Y643242D01*
G01X381775Y642802D02*
X383440Y644467D01*
G01X383000Y639263D02*
Y642294D01*
G01X381775Y639437D02*
Y642802D01*
G01X386992Y610172D02*
X388446Y608718D01*
G01X388217Y610680D02*
X389671Y609226D01*
G01X386992Y618010D02*
Y610172D01*
G01X388217Y617502D02*
Y610680D01*
G01X389750Y620768D02*
X386992Y618010D01*
G01X390975Y620260D02*
X388217Y617502D01*
G01X389750Y641121D02*
Y620768D01*
G01X390975Y641629D02*
Y620260D01*
G01X387629Y643242D02*
X389750Y641121D01*
G01X388137Y644467D02*
X390975Y641629D01*
G01X383948Y643242D02*
X387629D01*
G01X383440Y644467D02*
X388137D01*
G01X383000Y642294D02*
X383948Y643242D01*
G01X381775Y642802D02*
X383440Y644467D01*
G01X383000Y639263D02*
Y642294D01*
G01X381775Y639437D02*
Y642802D01*
G01X388217Y610680D02*
X389671Y609226D01*
G01X386992Y610172D02*
X388446Y608718D01*
G01X388217Y617502D02*
Y610680D01*
G01X386992Y618010D02*
Y610172D01*
G01X390975Y620260D02*
X388217Y617502D01*
G01X389750Y620768D02*
X386992Y618010D01*
G01X390975Y641629D02*
Y620260D01*
G01X389750Y641121D02*
Y620768D01*
G01X388137Y644467D02*
X390975Y641629D01*
G01X387629Y643242D02*
X389750Y641121D01*
G01X383440Y644467D02*
X388137D01*
G01X383948Y643242D02*
X387629D01*
G01X381775Y642802D02*
X383440Y644467D01*
G01X383000Y642294D02*
X383948Y643242D01*
G01X381775Y639437D02*
Y642802D01*
G01X383000Y639263D02*
Y642294D01*
G01X386992Y610172D02*
X388446Y608718D01*
G01X388217Y610680D02*
X389671Y609226D01*
G01X386992Y618010D02*
Y610172D01*
G01X388217Y617502D02*
Y610680D01*
G01X389750Y620768D02*
X386992Y618010D01*
G01X390975Y620260D02*
X388217Y617502D01*
G01X389750Y641121D02*
Y620768D01*
G01X390975Y641629D02*
Y620260D01*
G01X387629Y643242D02*
X389750Y641121D01*
G01X388137Y644467D02*
X390975Y641629D01*
G01X383948Y643242D02*
X387629D01*
G01X383440Y644467D02*
X388137D01*
G01X383000Y642294D02*
X383948Y643242D01*
G01X381775Y642802D02*
X383440Y644467D01*
G01X383000Y639263D02*
Y642294D01*
G01X381775Y639437D02*
Y642802D01*
G01X415693Y132852D02*
X410151Y133961D01*
G01X421033Y132852D02*
X415693D01*
G01D02*
X410151Y133961D01*
G01X421033Y132852D02*
X415693D01*
G01X420399Y121848D02*
X417738Y122377D01*
G01X420520Y123073D02*
X418215Y123532D01*
G01X423598Y121848D02*
X420399D01*
G01X423090Y123073D02*
X420520D01*
G01X425809Y124059D02*
X423598Y121848D01*
G01X424584Y124567D02*
X423090Y123073D01*
G01X425809Y126983D02*
Y124059D01*
G01X424584Y126983D02*
Y124567D01*
G01X426953Y128127D02*
G03X425809Y126983I0J-1144D01*
G01X426953Y129352D02*
G03X424584Y126983I0J-2369D01*
G01X427851Y128127D02*
X426953D01*
G01X428065Y129352D02*
X426953D01*
G01X420520Y123073D02*
X418215Y123532D01*
G01X420399Y121848D02*
X417738Y122377D01*
G01X423090Y123073D02*
X420520D01*
G01X423598Y121848D02*
X420399D01*
G01X424584Y124567D02*
X423090Y123073D01*
G01X425809Y124059D02*
X423598Y121848D01*
G01X424584Y126983D02*
Y124567D01*
G01X425809Y126983D02*
Y124059D01*
G01X426953Y129352D02*
G03X424584Y126983I0J-2369D01*
G01X426953Y128127D02*
G03X425809Y126983I0J-1144D01*
G01X428065Y129352D02*
X426953D01*
G01X427851Y128127D02*
X426953D01*
G01X430116Y117261D02*
X417203D01*
G01X429608Y118486D02*
X417573D01*
G01X432896Y120041D02*
X430116Y117261D01*
G01X431671Y120549D02*
X429608Y118486D01*
G01X432896Y131708D02*
Y120041D01*
G01X431671Y131708D02*
Y120549D01*
G01X434040Y132852D02*
G03X432896Y131708I0J-1144D01*
G01X434040Y134077D02*
G03X431671Y131708I0J-2369D01*
G01X434938Y132852D02*
X434040D01*
G01X429608Y118486D02*
X417573D01*
G01X430116Y117261D02*
X417203D01*
G01X431671Y120549D02*
X429608Y118486D01*
G01X432896Y120041D02*
X430116Y117261D01*
G01X431671Y131708D02*
Y120549D01*
G01X432896Y131708D02*
Y120041D01*
G01X434040Y134077D02*
G03X431671Y131708I0J-2369D01*
G01X434040Y132852D02*
G03X432896Y131708I0J-1144D01*
G01X434938Y132852D02*
X434040D01*
G01X431982Y112761D02*
X415177D01*
G01X431474Y113986D02*
X415548D01*
G01X439982Y120761D02*
X431982Y112761D01*
G01X438757Y121269D02*
X431474Y113986D01*
G01X439982Y126983D02*
Y120761D01*
G01X438757Y126983D02*
Y121269D01*
G01X441126Y128127D02*
G03X439982Y126983I0J-1144D01*
G01X441126Y129352D02*
G03X438757Y126983I0J-2369D01*
G01X442024Y128127D02*
X441126D01*
G01X442238Y129352D02*
X441126D01*
G01X431474Y113986D02*
X415548D01*
G01X431982Y112761D02*
X415177D01*
G01X438757Y121269D02*
X431474Y113986D01*
G01X439982Y120761D02*
X431982Y112761D01*
G01X438757Y126983D02*
Y121269D01*
G01X439982Y126983D02*
Y120761D01*
G01X441126Y129352D02*
G03X438757Y126983I0J-2369D01*
G01X441126Y128127D02*
G03X439982Y126983I0J-1144D01*
G01X442238Y129352D02*
X441126D01*
G01X442024Y128127D02*
X441126D01*
G01X436386Y108261D02*
X412786D01*
G01X435878Y109486D02*
X413158D01*
G01X447069Y118944D02*
X436386Y108261D01*
G01X445844Y119452D02*
X435878Y109486D01*
G01X447069Y131708D02*
Y118944D01*
G01X445844Y131708D02*
Y119452D01*
G01X448213Y132852D02*
G03X447069Y131708I0J-1144D01*
G01X448213Y134077D02*
G03X445844Y131708I0J-2369D01*
G01X449111Y132852D02*
X448213D01*
G01X435878Y109486D02*
X413158D01*
G01X436386Y108261D02*
X412786D01*
G01X445844Y119452D02*
X435878Y109486D01*
G01X447069Y118944D02*
X436386Y108261D01*
G01X445844Y131708D02*
Y119452D01*
G01X447069Y131708D02*
Y118944D01*
G01X448213Y134077D02*
G03X445844Y131708I0J-2369D01*
G01X448213Y132852D02*
G03X447069Y131708I0J-1144D01*
G01X449111Y132852D02*
X448213D01*
G01X439111Y103761D02*
X407317D01*
G01X438603Y104986D02*
X407692D01*
G01X454155Y118805D02*
X439111Y103761D01*
G01X452930Y119313D02*
X438603Y104986D01*
G01X454155Y126983D02*
Y118805D01*
G01X452930Y126983D02*
Y119313D01*
G01X455299Y128127D02*
G03X454155Y126983I0J-1144D01*
G01X455299Y129352D02*
G03X452930Y126983I0J-2369D01*
G01X456197Y128127D02*
X455299D01*
G01X456411Y129352D02*
X455299D01*
G01X438603Y104986D02*
X407692D01*
G01X439111Y103761D02*
X407317D01*
G01X452930Y119313D02*
X438603Y104986D01*
G01X454155Y118805D02*
X439111Y103761D01*
G01X452930Y126983D02*
Y119313D01*
G01X454155Y126983D02*
Y118805D01*
G01X455299Y129352D02*
G03X452930Y126983I0J-2369D01*
G01X455299Y128127D02*
G03X454155Y126983I0J-1144D01*
G01X456411Y129352D02*
X455299D01*
G01X456197Y128127D02*
X455299D01*
G01X461242Y118972D02*
X439980Y97710D01*
G01X460017Y119480D02*
X439472Y98935D01*
G01X461242Y131708D02*
Y118972D01*
G01X460017Y131708D02*
Y119480D01*
G01X462386Y132852D02*
G03X461242Y131708I0J-1144D01*
G01X462386Y134077D02*
G03X460017Y131708I0J-2369D01*
G01X463284Y132852D02*
X462386D01*
G01X460017Y119480D02*
X439472Y98935D01*
G01X461242Y118972D02*
X439980Y97710D01*
G01X460017Y131708D02*
Y119480D01*
G01X461242Y131708D02*
Y118972D01*
G01X462386Y134077D02*
G03X460017Y131708I0J-2369D01*
G01X462386Y132852D02*
G03X461242Y131708I0J-1144D01*
G01X463284Y132852D02*
X462386D01*
G01X468329Y112249D02*
X449001Y92921D01*
G01X467104Y112757D02*
X448493Y94146D01*
G01X468329Y126983D02*
Y112249D01*
G01X467104Y126983D02*
Y112757D01*
G01X469473Y128127D02*
G03X468329Y126983I0J-1144D01*
G01X469473Y129352D02*
G03X467104Y126983I0J-2369D01*
G01X470371Y128127D02*
X469473D01*
G01X470585Y129352D02*
X469473D01*
G01X467104Y112757D02*
X448493Y94146D01*
G01X468329Y112249D02*
X449001Y92921D01*
G01X467104Y126983D02*
Y112757D01*
G01X468329Y126983D02*
Y112249D01*
G01X469473Y129352D02*
G03X467104Y126983I0J-2369D01*
G01X469473Y128127D02*
G03X468329Y126983I0J-1144D01*
G01X470585Y129352D02*
X469473D01*
G01X470371Y128127D02*
X469473D01*
G01X468945Y105249D02*
X475730Y112034D01*
G01X476955Y111526D02*
X452571Y87142D01*
G01X468096Y105249D02*
X468945D01*
G01X476955Y111526D02*
X452571Y87142D01*
G01X465657Y101961D02*
X466876Y103180D01*
G01X476955Y111526D02*
X452571Y87142D01*
G01X464808Y101961D02*
X465657D01*
G01X476955Y111526D02*
X452571Y87142D01*
G01X462369Y98673D02*
X463588Y99892D01*
G01X476955Y111526D02*
X452571Y87142D01*
G01X461520Y98673D02*
X462369D01*
G01X476955Y111526D02*
X452571Y87142D01*
G01X459081Y95385D02*
X460300Y96604D01*
G01X476955Y111526D02*
X452571Y87142D01*
G01X458232Y95385D02*
X459081D01*
G01X476955Y111526D02*
X452571Y87142D01*
G01X452063Y88367D02*
X457012Y93316D01*
G01X476955Y111526D02*
X452571Y87142D01*
G01X419898Y88367D02*
X452063D01*
G01X415248D02*
X416973D01*
G01X410598D02*
X412323D01*
G01X405948D02*
X407673D01*
G01X419898D02*
X452063D01*
G01X415248D02*
X416973D01*
G01X410598D02*
X412323D01*
G01X405948D02*
X407673D01*
G01X476955Y111526D02*
X452571Y87142D01*
G01X468945Y105249D02*
X475730Y112034D01*
G01X468096Y105249D02*
X468945D01*
G01X465657Y101961D02*
X466876Y103180D01*
G01X464808Y101961D02*
X465657D01*
G01X462369Y98673D02*
X463588Y99892D01*
G01X461520Y98673D02*
X462369D01*
G01X459081Y95385D02*
X460300Y96604D01*
G01X458232Y95385D02*
X459081D01*
G01X452063Y88367D02*
X457012Y93316D01*
G01X415815Y134077D02*
X410629Y135115D01*
G01X420913Y134077D02*
X415815D01*
G01D02*
X410629Y135115D01*
G01X420913Y134077D02*
X415815D01*
G01X435152D02*
X434040D01*
G01X435152D02*
X434040D01*
G01X449325D02*
X448213D01*
G01X449325D02*
X448213D01*
G01X463498D02*
X462386D01*
G01X463498D02*
X462386D01*
G01X503762Y118210D02*
Y145881D01*
G01X502537Y117702D02*
Y145881D01*
G01X534487Y87485D02*
X503762Y118210D01*
G01X533979Y86260D02*
X502537Y117702D01*
G01X555880Y87485D02*
X534487D01*
G01X555372Y86260D02*
X533979D01*
G01X502537Y117702D02*
Y145881D01*
G01X503762Y118210D02*
Y145881D01*
G01X533979Y86260D02*
X502537Y117702D01*
G01X534487Y87485D02*
X503762Y118210D01*
G01X555372Y86260D02*
X533979D01*
G01X555880Y87485D02*
X534487D01*
G01X510848Y117489D02*
Y141157D01*
G01X509623Y116981D02*
Y141157D01*
G01X536352Y91985D02*
X510848Y117489D01*
G01X535844Y90760D02*
X509623Y116981D01*
G01X573806Y91985D02*
X536352D01*
G01X574181Y90760D02*
X535844D01*
G01X509623Y116981D02*
Y141157D01*
G01X510848Y117489D02*
Y141157D01*
G01X535844Y90760D02*
X509623Y116981D01*
G01X536352Y91985D02*
X510848Y117489D01*
G01X574181Y90760D02*
X535844D01*
G01X573806Y91985D02*
X536352D01*
G01X517935Y116883D02*
Y145881D01*
G01X516710Y116375D02*
Y145881D01*
G01X538179Y96639D02*
X517935Y116883D01*
G01X537671Y95414D02*
X516710Y116375D01*
G01D02*
Y145881D01*
G01X517935Y116883D02*
Y145881D01*
G01X537671Y95414D02*
X516710Y116375D01*
G01X538179Y96639D02*
X517935Y116883D01*
G01X525022Y116602D02*
Y141157D01*
G01X523797Y116094D02*
Y141157D01*
G01X540365Y101259D02*
X525022Y116602D01*
G01X539857Y100034D02*
X523797Y116094D01*
G01D02*
Y141157D01*
G01X525022Y116602D02*
Y141157D01*
G01X539857Y100034D02*
X523797Y116094D01*
G01X540365Y101259D02*
X525022Y116602D01*
G01X535396Y112880D02*
X542517Y105759D01*
G01X530883Y115660D02*
X542009Y104534D01*
G01X533328Y114948D02*
X534176D01*
G01X530883Y115660D02*
X542009Y104534D01*
G01X532108Y116168D02*
X533328Y114948D01*
G01X530883Y115660D02*
X542009Y104534D01*
G01X532108Y145881D02*
Y116168D01*
G01X530883Y145881D02*
Y115660D01*
G01D02*
X542009Y104534D01*
G01X535396Y112880D02*
X542517Y105759D01*
G01X533328Y114948D02*
X534176D01*
G01X532108Y116168D02*
X533328Y114948D01*
G01X530883Y145881D02*
Y115660D01*
G01X532108Y145881D02*
Y116168D01*
G01X475730Y112034D02*
Y167965D01*
G01X476955D02*
Y111526D01*
G01Y167965D02*
Y111526D01*
G01X475730Y112034D02*
Y167965D01*
G01X504906Y147025D02*
X505804D01*
G01X504906Y148250D02*
X506018D01*
G01X503762Y145881D02*
G02X504906Y147025I1144J0D01*
G01X502537Y145881D02*
G02X504906Y148250I2369J0D01*
G01D02*
X506018D01*
G01X504906Y147025D02*
X505804D01*
G01X502537Y145881D02*
G02X504906Y148250I2369J0D01*
G01X503762Y145881D02*
G02X504906Y147025I1144J0D01*
G01X511992Y142301D02*
X512890D01*
G01X511992Y143526D02*
X513104D01*
G01X510848Y141157D02*
G02X511992Y142301I1144J0D01*
G01X509623Y141157D02*
G02X511992Y143526I2369J0D01*
G01D02*
X513104D01*
G01X511992Y142301D02*
X512890D01*
G01X509623Y141157D02*
G02X511992Y143526I2369J0D01*
G01X510848Y141157D02*
G02X511992Y142301I1144J0D01*
G01X519079Y147025D02*
X519977D01*
G01X519079Y148250D02*
X520191D01*
G01X517935Y145881D02*
G02X519079Y147025I1144J0D01*
G01X516710Y145881D02*
G02X519079Y148250I2369J0D01*
G01D02*
X520191D01*
G01X519079Y147025D02*
X519977D01*
G01X516710Y145881D02*
G02X519079Y148250I2369J0D01*
G01X517935Y145881D02*
G02X519079Y147025I1144J0D01*
G01X526166Y142301D02*
X527064D01*
G01X526166Y143526D02*
X527278D01*
G01X525022Y141157D02*
G02X526166Y142301I1144J0D01*
G01X523797Y141157D02*
G02X526166Y143526I2369J0D01*
G01D02*
X527278D01*
G01X526166Y142301D02*
X527064D01*
G01X523797Y141157D02*
G02X526166Y143526I2369J0D01*
G01X525022Y141157D02*
G02X526166Y142301I1144J0D01*
G01X533252Y147025D02*
G03X532108Y145881I0J-1144D01*
G01X533252Y148250D02*
G03X530883Y145881I0J-2369D01*
G01X534150Y147025D02*
X533252D01*
G01X534364Y148250D02*
X533252D01*
G01D02*
G03X530883Y145881I0J-2369D01*
G01X533252Y147025D02*
G03X532108Y145881I0J-1144D01*
G01X534364Y148250D02*
X533252D01*
G01X534150Y147025D02*
X533252D01*
G01X473047Y170648D02*
X471935D01*
G01X472149Y171873D02*
X473047D01*
G01X475730Y167965D02*
G03X473047Y170648I-2683J0D01*
G01Y171873D02*
G02X476955Y167965I0J-3908D01*
G01X473047Y171873D02*
G02X476955Y167965I0J-3908D01*
G01X475730D02*
G03X473047Y170648I-2683J0D01*
G01X472149Y171873D02*
X473047D01*
G01Y170648D02*
X471935D01*
G01X588214Y185931D02*
X577016Y129933D01*
G01X588214Y185931D02*
X577016Y129933D01*
G01X588214Y185931D02*
X577016Y129933D01*
G01X588214Y185931D02*
X577016Y129933D01*
G01X588214Y185931D02*
X577016Y129933D01*
G01X588214Y185931D02*
X577016Y129933D01*
G01X588214Y185931D02*
X577016Y129933D01*
G01X588214Y185931D02*
X577016Y129933D01*
G01X575862Y130411D02*
X576200Y132103D01*
G01X588214Y185931D02*
X577016Y129933D01*
G01X567720Y118187D02*
X575862Y130411D01*
G01X577016Y129933D02*
X568604Y117304D01*
G01X562581Y114759D02*
X567720Y118187D01*
G01X568604Y117304D02*
X562953Y113534D01*
G01X550342Y114759D02*
X562581D01*
G01X562953Y113534D02*
X549834D01*
G01X546281Y118820D02*
X550342Y114759D01*
G01X549834Y113534D02*
X545056Y118312D01*
G01X546281Y145881D02*
Y118820D01*
G01X545056Y118312D02*
Y145881D01*
G01Y118312D02*
Y145881D01*
G01X546281D02*
Y118820D01*
G01X549834Y113534D02*
X545056Y118312D01*
G01X546281Y118820D02*
X550342Y114759D01*
G01X562953Y113534D02*
X549834D01*
G01X550342Y114759D02*
X562581D01*
G01X568604Y117304D02*
X562953Y113534D01*
G01X562581Y114759D02*
X567720Y118187D01*
G01X577016Y129933D02*
X568604Y117304D01*
G01X567720Y118187D02*
X575862Y130411D01*
G01X588214Y185931D02*
X577016Y129933D01*
G01X575862Y130411D02*
X576200Y132103D01*
G01X572032Y131306D02*
X582494Y183681D01*
G01X572032Y131306D02*
X582494Y183681D01*
G01X572032Y131306D02*
X582494Y183681D01*
G01X572032Y131306D02*
X582494Y183681D01*
G01X572032Y131306D02*
X582494Y183681D01*
G01X572032Y131306D02*
X582494Y183681D01*
G01X572032Y131306D02*
X582494Y183681D01*
G01X572032Y131306D02*
X582494Y183681D01*
G01X570878Y131784D02*
X571216Y133476D01*
G01X572032Y131306D02*
X582494Y183681D01*
G01X564071Y121561D02*
X570877Y131784D01*
G01X564957Y120681D02*
X572032Y131306D01*
G01X560660Y119259D02*
X564071Y121561D01*
G01X561035Y118034D02*
X564957Y120681D01*
G01X554469Y119259D02*
X560660D01*
G01X553961Y118034D02*
X561035D01*
G01X553368Y120360D02*
X554469Y119259D01*
G01X552143Y119852D02*
X553961Y118034D01*
G01X553368Y141157D02*
Y120360D01*
G01X552143Y141157D02*
Y119852D01*
G01X572032Y131306D02*
X582494Y183681D01*
G01X570878Y131784D02*
X571216Y133476D01*
G01X564957Y120681D02*
X572032Y131306D01*
G01X564071Y121561D02*
X570877Y131784D01*
G01X561035Y118034D02*
X564957Y120681D01*
G01X560660Y119259D02*
X564071Y121561D01*
G01X553961Y118034D02*
X561035D01*
G01X554469Y119259D02*
X560660D01*
G01X552143Y119852D02*
X553961Y118034D01*
G01X553368Y120360D02*
X554469Y119259D01*
G01X552143Y141157D02*
Y119852D01*
G01X553368Y141157D02*
Y120360D01*
G01X593199Y184076D02*
X581388Y125731D01*
G01X593199Y184076D02*
X581388Y125731D01*
G01X593199Y184076D02*
X581388Y125731D01*
G01X593199Y184076D02*
X581388Y125731D01*
G01X593199Y184076D02*
X581388Y125731D01*
G01X593199Y184076D02*
X581388Y125731D01*
G01X593199Y184076D02*
X581388Y125731D01*
G01X581157Y130769D02*
X581499Y132460D01*
G01X593199Y184076D02*
X581388Y125731D01*
G01X580234Y126211D02*
X580576Y127902D01*
G01X593199Y184076D02*
X581388Y125731D01*
G01X578570Y123714D02*
X580234Y126211D01*
G01X581388Y125731D02*
X574294Y115092D01*
G01X575990Y119845D02*
X576947Y121280D01*
G01X581388Y125731D02*
X574294Y115092D01*
G01X573410Y115976D02*
X574367Y117411D01*
G01X581388Y125731D02*
X574294Y115092D01*
G01X564842Y110259D02*
X573410Y115976D01*
G01X574294Y115092D02*
X565214Y109034D01*
G01X548477Y110259D02*
X564842D01*
G01X565214Y109034D02*
X547969D01*
G01X539195Y119541D02*
X548477Y110259D01*
G01X547969Y109034D02*
X537970Y119033D01*
G01X539195Y141157D02*
Y119541D01*
G01X537970Y119033D02*
Y141157D01*
G01Y119033D02*
Y141157D01*
G01X539195D02*
Y119541D01*
G01X547969Y109034D02*
X537970Y119033D01*
G01X539195Y119541D02*
X548477Y110259D01*
G01X565214Y109034D02*
X547969D01*
G01X548477Y110259D02*
X564842D01*
G01X574294Y115092D02*
X565214Y109034D01*
G01X564842Y110259D02*
X573410Y115976D01*
G01X581388Y125731D02*
X574294Y115092D01*
G01X578570Y123714D02*
X580234Y126211D01*
G01X575990Y119845D02*
X576947Y121280D01*
G01X573410Y115976D02*
X574367Y117411D01*
G01X593199Y184076D02*
X581388Y125731D01*
G01X581157Y130769D02*
X581499Y132460D01*
G01X580234Y126211D02*
X580576Y127902D01*
G01X557265Y86100D02*
X555880Y87485D01*
G01X556757Y84875D02*
X555372Y86260D01*
G01X565867Y86100D02*
X557265D01*
G01X566375Y84875D02*
X556757D01*
G01X566992Y87225D02*
X565867Y86100D01*
G01X567500Y86000D02*
X566375Y84875D01*
G01X575546Y87225D02*
X566992D01*
G01X575917Y86000D02*
X567500D01*
G01X589336Y96418D02*
X575546Y87225D01*
G01X590220Y95534D02*
X575917Y86000D01*
G01X602947Y116835D02*
X589336Y96418D01*
G01X604101Y116357D02*
X590220Y95534D01*
G01X556757Y84875D02*
X555372Y86260D01*
G01X557265Y86100D02*
X555880Y87485D01*
G01X566375Y84875D02*
X556757D01*
G01X565867Y86100D02*
X557265D01*
G01X567500Y86000D02*
X566375Y84875D01*
G01X566992Y87225D02*
X565867Y86100D01*
G01X575917Y86000D02*
X567500D01*
G01X575546Y87225D02*
X566992D01*
G01X590220Y95534D02*
X575917Y86000D01*
G01X589336Y96418D02*
X575546Y87225D01*
G01X604101Y116357D02*
X590220Y95534D01*
G01X602947Y116835D02*
X589336Y96418D01*
G01X586461Y100521D02*
X573806Y91985D01*
G01X587344Y99638D02*
X574181Y90760D01*
G01X598648Y118591D02*
X586461Y100521D01*
G01X599802Y118109D02*
X587344Y99638D01*
G01X598986Y120283D02*
X598648Y118591D01*
G01X612949Y183843D02*
X599802Y118109D01*
G01X599898Y124842D02*
X599560Y123151D01*
G01X612949Y183843D02*
X599802Y118109D01*
G01X600810Y129402D02*
X600472Y127710D01*
G01X612949Y183843D02*
X599802Y118109D01*
G01X601722Y133962D02*
X601384Y132270D01*
G01X612949Y183843D02*
X599802Y118109D01*
G01X612949Y183843D02*
X599802Y118109D01*
G01X587344Y99638D02*
X574181Y90760D01*
G01X586461Y100521D02*
X573806Y91985D01*
G01X599802Y118109D02*
X587344Y99638D01*
G01X598648Y118591D02*
X586461Y100521D01*
G01X612949Y183843D02*
X599802Y118109D01*
G01X598986Y120283D02*
X598648Y118591D01*
G01X599898Y124842D02*
X599560Y123151D01*
G01X600810Y129402D02*
X600472Y127710D01*
G01X601722Y133962D02*
X601384Y132270D01*
G01X572008Y96639D02*
X538179D01*
G01X572379Y95414D02*
X537671D01*
G01X583439Y104260D02*
X572008Y96639D01*
G01X584323Y103376D02*
X572379Y95414D01*
G01X584396Y105695D02*
X583439Y104260D01*
G01X594754Y119022D02*
X584323Y103376D01*
G01X586975Y109564D02*
X586019Y108129D01*
G01X594754Y119022D02*
X584323Y103376D01*
G01X589555Y113433D02*
X588598Y111998D01*
G01X594754Y119022D02*
X584323Y103376D01*
G01X593600Y119500D02*
X591178Y115867D01*
G01X594754Y119022D02*
X584323Y103376D01*
G01X593938Y121192D02*
X593600Y119500D01*
G01X607599Y183275D02*
X594754Y119022D01*
G01X594849Y125751D02*
X594511Y124060D01*
G01X607599Y183275D02*
X594754Y119022D01*
G01X595761Y130311D02*
X595423Y128620D01*
G01X607599Y183275D02*
X594754Y119022D01*
G01X596672Y134871D02*
X596334Y133179D01*
G01X607599Y183275D02*
X594754Y119022D01*
G01X607599Y183275D02*
X594754Y119022D01*
G01X607599Y183275D02*
X594754Y119022D01*
G01X607599Y183275D02*
X594754Y119022D01*
G01X607599Y183275D02*
X594754Y119022D01*
G01X607599Y183275D02*
X594754Y119022D01*
G01X607599Y183275D02*
X594754Y119022D01*
G01X572379Y95414D02*
X537671D01*
G01X572008Y96639D02*
X538179D01*
G01X584323Y103376D02*
X572379Y95414D01*
G01X583439Y104260D02*
X572008Y96639D01*
G01X594754Y119022D02*
X584323Y103376D01*
G01X584396Y105695D02*
X583439Y104260D01*
G01X586975Y109564D02*
X586019Y108129D01*
G01X589555Y113433D02*
X588598Y111998D01*
G01X593600Y119500D02*
X591178Y115867D01*
G01X607599Y183275D02*
X594754Y119022D01*
G01X593938Y121192D02*
X593600Y119500D01*
G01X594849Y125751D02*
X594511Y124060D01*
G01X595761Y130311D02*
X595423Y128620D01*
G01X596672Y134871D02*
X596334Y133179D01*
G01X570431Y101259D02*
X540365D01*
G01X570802Y100034D02*
X539857D01*
G01X578896Y106904D02*
X570431Y101259D01*
G01X579780Y106020D02*
X570802Y100034D01*
G01X588806Y121772D02*
X578896Y106904D01*
G01X589960Y121294D02*
X579780Y106020D01*
G01X601259Y184053D02*
X588806Y121772D01*
G01X602509Y184053D02*
X589960Y121294D01*
G01X570802Y100034D02*
X539857D01*
G01X570431Y101259D02*
X540365D01*
G01X579780Y106020D02*
X570802Y100034D01*
G01X578896Y106904D02*
X570431Y101259D01*
G01X589960Y121294D02*
X579780Y106020D01*
G01X588806Y121772D02*
X578896Y106904D01*
G01X602509Y184053D02*
X589960Y121294D01*
G01X601259Y184053D02*
X588806Y121772D01*
G01X584581Y124055D02*
X596606Y184239D01*
G01X585735Y123577D02*
X597856Y184239D01*
G01X577465Y113378D02*
X584581Y124055D01*
G01X576316Y109443D02*
X585735Y123577D01*
G01X576750Y112305D02*
X577465Y113378D01*
G01X576316Y109443D02*
X585735Y123577D01*
G01X575432Y110327D02*
X576750Y112305D01*
G01X576316Y109443D02*
X585735Y123577D01*
G01X568580Y105759D02*
X575432Y110327D01*
G01X568951Y104534D02*
X576316Y109443D01*
G01X542517Y105759D02*
X568580D01*
G01X542009Y104534D02*
X568951D01*
G01X585735Y123577D02*
X597856Y184239D01*
G01X584581Y124055D02*
X596606Y184239D01*
G01X576316Y109443D02*
X585735Y123577D01*
G01X577465Y113378D02*
X584581Y124055D01*
G01X576750Y112305D02*
X577465Y113378D01*
G01X575432Y110327D02*
X576750Y112305D01*
G01X568951Y104534D02*
X576316Y109443D01*
G01X568580Y105759D02*
X575432Y110327D01*
G01X542009Y104534D02*
X568951D01*
G01X542517Y105759D02*
X568580D01*
G01X586964Y185931D02*
X577599Y232810D01*
G01X578849D02*
X588214Y185931D01*
G01X586626Y184239D02*
X586964Y185931D01*
G01X585714Y179680D02*
X586052Y181371D01*
G01X584802Y175120D02*
X585140Y176812D01*
G01X583890Y170560D02*
X584229Y172252D01*
G01X579509Y148650D02*
X583317Y167692D01*
G01X578597Y144090D02*
X578936Y145782D01*
G01X577686Y139530D02*
X578024Y141222D01*
G01X576774Y134971D02*
X577112Y136662D01*
G01X547425Y147025D02*
G03X546281Y145881I0J-1144D01*
G01X545056D02*
G02X547425Y148250I2369J0D01*
G01X548323Y147025D02*
X547425D01*
G01Y148250D02*
X548537D01*
G01X547425D02*
X548537D01*
G01X548323Y147025D02*
X547425D01*
G01X545056Y145881D02*
G02X547425Y148250I2369J0D01*
G01Y147025D02*
G03X546281Y145881I0J-1144D01*
G01X586626Y184239D02*
X586964Y185931D01*
G01X585714Y179680D02*
X586052Y181371D01*
G01X584802Y175120D02*
X585140Y176812D01*
G01X583890Y170560D02*
X584229Y172252D01*
G01X579509Y148650D02*
X583317Y167692D01*
G01X578597Y144090D02*
X578936Y145782D01*
G01X577686Y139530D02*
X578024Y141222D01*
G01X576774Y134971D02*
X577112Y136662D01*
G01X578849Y232810D02*
X588214Y185931D01*
G01X586964D02*
X577599Y232810D01*
G01X581247Y183702D02*
X572971Y232992D01*
G01X582494Y183681D02*
X574217Y232973D01*
G01X580909Y182010D02*
X581247Y183702D01*
G01X579998Y177450D02*
X580336Y179142D01*
G01X579088Y172890D02*
X579426Y174582D01*
G01X578177Y168331D02*
X578515Y170022D01*
G01X574521Y150024D02*
X577604Y165462D01*
G01X573610Y145464D02*
X573948Y147155D01*
G01X572699Y140904D02*
X573037Y142596D01*
G01X571789Y136344D02*
X572127Y138036D01*
G01X554512Y142301D02*
G03X553368Y141157I0J-1144D01*
G01X554512Y143526D02*
G03X552143Y141157I0J-2369D01*
G01X555410Y142301D02*
X554512D01*
G01X555624Y143526D02*
X554512D01*
G01X582494Y183681D02*
X574217Y232973D01*
G01X581247Y183702D02*
X572971Y232992D01*
G01X580909Y182010D02*
X581247Y183702D01*
G01X579998Y177450D02*
X580336Y179142D01*
G01X579088Y172890D02*
X579426Y174582D01*
G01X578177Y168331D02*
X578515Y170022D01*
G01X574521Y150024D02*
X577604Y165462D01*
G01X573610Y145464D02*
X573948Y147155D01*
G01X572699Y140904D02*
X573037Y142596D01*
G01X571789Y136344D02*
X572127Y138036D01*
G01X554512Y143526D02*
G03X552143Y141157I0J-2369D01*
G01X554512Y142301D02*
G03X553368Y141157I0J-1144D01*
G01X555624Y143526D02*
X554512D01*
G01X555410Y142301D02*
X554512D01*
G01X591949Y184077D02*
X582202Y232794D01*
G01X583452D02*
X593199Y184076D01*
G01X591607Y182386D02*
X591949Y184077D01*
G01X590684Y177829D02*
X591026Y179519D01*
G01X589761Y173271D02*
X590104Y174962D01*
G01X588839Y168714D02*
X589181Y170404D01*
G01X583925Y144443D02*
X588258Y165847D01*
G01X583003Y139885D02*
X583345Y141576D01*
G01X582080Y135327D02*
X582422Y137018D01*
G01X540339Y142301D02*
G03X539195Y141157I0J-1144D01*
G01X537970D02*
G02X540339Y143526I2369J0D01*
G01X541237Y142301D02*
X540339D01*
G01Y143526D02*
X541451D01*
G01X540339D02*
X541451D01*
G01X541237Y142301D02*
X540339D01*
G01X537970Y141157D02*
G02X540339Y143526I2369J0D01*
G01Y142301D02*
G03X539195Y141157I0J-1144D01*
G01X591607Y182386D02*
X591949Y184077D01*
G01X590684Y177829D02*
X591026Y179519D01*
G01X589761Y173271D02*
X590104Y174962D01*
G01X588839Y168714D02*
X589181Y170404D01*
G01X583925Y144443D02*
X588258Y165847D01*
G01X583003Y139885D02*
X583345Y141576D01*
G01X582080Y135327D02*
X582422Y137018D01*
G01X583452Y232794D02*
X593199Y184076D01*
G01X591949Y184077D02*
X582202Y232794D01*
G01X611699Y183843D02*
X602296Y136830D01*
G01X611699Y183843D02*
X602296Y136830D01*
G01X601791Y160480D02*
X597246Y137739D01*
G01X602702Y165040D02*
X602364Y163348D01*
G01X601791Y160480D02*
X597246Y137739D01*
G01X602702Y165040D02*
X602364Y163348D01*
G01X591512Y232791D02*
X601259Y184053D01*
G01X592762Y232791D02*
X602509Y184053D01*
G01X592762Y232791D02*
X602509Y184053D01*
G01X591512Y232791D02*
X601259Y184053D01*
G01X596606Y184239D02*
X586898Y232799D01*
G01X597856Y184239D02*
X588148Y232799D01*
G01X597856Y184239D02*
X588148Y232799D01*
G01X596606Y184239D02*
X586898Y232799D01*
G01X592290Y299992D02*
X578849Y232810D01*
G01X577599D02*
X584367Y266642D01*
G01X592290Y299992D02*
X578849Y232810D01*
G01X592290Y299992D02*
X578849Y232810D01*
G01X577599D02*
X584367Y266642D01*
G01X576499Y250616D02*
X580981Y272998D01*
G01X578199Y252863D02*
X582183Y272755D01*
G01X576249Y249372D02*
X576498Y250616D01*
G01X577203Y247889D02*
X578199Y252862D01*
G01X576001Y248129D02*
X576249Y249372D01*
G01X577203Y247889D02*
X578199Y252862D01*
G01X572971Y232992D02*
X576001Y248129D01*
G01X574217Y232973D02*
X577203Y247889D01*
G01X578199Y252863D02*
X582183Y272755D01*
G01X576499Y250616D02*
X580981Y272998D01*
G01X577203Y247889D02*
X578199Y252862D01*
G01X576249Y249372D02*
X576498Y250616D01*
G01X576001Y248129D02*
X576249Y249372D01*
G01X574217Y232973D02*
X577203Y247889D01*
G01X572971Y232992D02*
X576001Y248129D01*
G01X596443Y297768D02*
X583452Y232794D01*
G01X582202D02*
X588745Y265521D01*
G01X596443Y297768D02*
X583452Y232794D01*
G01X596443Y297768D02*
X583452Y232794D01*
G01X582202D02*
X588745Y265521D01*
G01X602401Y230349D02*
X602739Y228658D01*
G01X601489Y234909D02*
X601827Y233217D01*
G01X612234Y290189D02*
X601489Y234909D01*
G01X602401Y230349D02*
X602739Y228658D01*
G01X601489Y234909D02*
X601827Y233217D01*
G01X612234Y290189D02*
X601489Y234909D01*
G01X596285Y233630D02*
X606348Y183281D01*
G01X597535Y233630D02*
X607599Y183277D01*
G01X608014Y292328D02*
X596285Y233630D01*
G01X609168Y291850D02*
X597535Y233630D01*
G01D02*
X607599Y183277D01*
G01X596285Y233630D02*
X606348Y183281D01*
G01X609168Y291850D02*
X597535Y233630D01*
G01X608014Y292328D02*
X596285Y233630D01*
G01X603848Y294482D02*
X591512Y232791D01*
G01X605002Y294005D02*
X592762Y232791D01*
G01X605002Y294005D02*
X592762Y232791D01*
G01X603848Y294482D02*
X591512Y232791D01*
G01X593272Y264654D02*
X599645Y296506D01*
G01X588148Y232799D02*
X600799Y296028D01*
G01X586898Y232799D02*
X593272Y264654D01*
G01X588148Y232799D02*
X600799Y296028D01*
G01X588148Y232799D02*
X600799Y296028D01*
G01X593272Y264654D02*
X599645Y296506D01*
G01X586898Y232799D02*
X593272Y264654D01*
G01X597064Y309074D02*
X636915Y335541D01*
G01X637593Y334520D02*
X597939Y308183D01*
G01X594104Y304781D02*
X597064Y309074D01*
G01X597939Y308183D02*
X595114Y304087D01*
G01X592692Y302735D02*
X594104Y304781D01*
G01X595113Y304086D02*
X592290Y299992D01*
G01X591138Y300480D02*
X592692Y302735D01*
G01X595113Y304086D02*
X592290Y299992D01*
G01X584367Y266642D02*
X591138Y300480D01*
G01X584367Y266642D02*
X591138Y300480D01*
G01X595113Y304086D02*
X592290Y299992D01*
G01X592692Y302735D02*
X594104Y304781D01*
G01X591138Y300480D02*
X592692Y302735D01*
G01X597939Y308183D02*
X595114Y304087D01*
G01X594104Y304781D02*
X597064Y309074D01*
G01X637593Y334520D02*
X597939Y308183D01*
G01X597064Y309074D02*
X636915Y335541D01*
G01X594845Y313962D02*
X679009Y368947D01*
G01X595710Y313063D02*
X679481Y367792D01*
G01X586957Y302835D02*
X594845Y313962D01*
G01X588107Y302339D02*
X595710Y313063D01*
G01X580981Y272998D02*
X586957Y302835D01*
G01X582183Y272755D02*
X588107Y302339D01*
G01X595710Y313063D02*
X679481Y367792D01*
G01X594845Y313962D02*
X679009Y368947D01*
G01X588107Y302339D02*
X595710Y313063D01*
G01X586957Y302835D02*
X594845Y313962D01*
G01X582183Y272755D02*
X588107Y302339D01*
G01X580981Y272998D02*
X586957Y302835D01*
G01X600327Y305801D02*
X681872Y359978D01*
G01X682349Y358824D02*
X601210Y304916D01*
G01X595289Y298246D02*
X600327Y305801D01*
G01X601210Y304916D02*
X596443Y297768D01*
G01X588745Y265521D02*
X595289Y298246D01*
G01X588745Y265521D02*
X595289Y298246D01*
G01X601210Y304916D02*
X596443Y297768D01*
G01X595289Y298246D02*
X600327Y305801D01*
G01X682349Y358824D02*
X601210Y304916D01*
G01X600327Y305801D02*
X681872Y359978D01*
G01X599645Y296506D02*
X603548Y302359D01*
G01X600799Y296028D02*
X604432Y301475D01*
G01X600799Y296028D02*
X604432Y301475D01*
G01X599645Y296506D02*
X603548Y302359D01*
G01X616638Y185282D02*
X602947Y116835D01*
G01X617888Y185282D02*
X604101Y116357D01*
G01X617888Y185282D02*
X604101Y116357D01*
G01X616638Y185282D02*
X602947Y116835D01*
G01X616301Y186974D02*
X616638Y185282D01*
G01X607729Y236247D02*
X617888Y185282D01*
G01X615392Y191534D02*
X615729Y189842D01*
G01X607729Y236247D02*
X617888Y185282D01*
G01X614483Y196094D02*
X614820Y194403D01*
G01X607729Y236247D02*
X617888Y185282D01*
G01X613574Y200655D02*
X613911Y198963D01*
G01X607729Y236247D02*
X617888Y185282D01*
G01X607729Y236247D02*
X617888Y185282D01*
G01X607729Y236247D02*
X617888Y185282D01*
G01X607729Y236247D02*
X617888Y185282D01*
G01X607729Y236247D02*
X617888Y185282D01*
G01X607729Y236247D02*
X617888Y185282D01*
G01X616301Y186974D02*
X616638Y185282D01*
G01X615392Y191534D02*
X615729Y189842D01*
G01X614483Y196094D02*
X614820Y194403D01*
G01X613574Y200655D02*
X613911Y198963D01*
G01X611361Y185535D02*
X611699Y183843D01*
G01X602738Y234912D02*
X612949Y183843D01*
G01X610449Y190094D02*
X610787Y188403D01*
G01X602738Y234912D02*
X612949Y183843D01*
G01X609538Y194654D02*
X609876Y192963D01*
G01X602738Y234912D02*
X612949Y183843D01*
G01X608626Y199214D02*
X608964Y197522D01*
G01X602738Y234912D02*
X612949Y183843D01*
G01X602738Y234912D02*
X612949Y183843D01*
G01X602738Y234912D02*
X612949Y183843D01*
G01X602738Y234912D02*
X612949Y183843D01*
G01X602738Y234912D02*
X612949Y183843D01*
G01X602738Y234912D02*
X612949Y183843D01*
G01X611361Y185535D02*
X611699Y183843D01*
G01X610449Y190094D02*
X610787Y188403D01*
G01X609538Y194654D02*
X609876Y192963D01*
G01X608626Y199214D02*
X608964Y197522D01*
G01X603614Y169600D02*
X603276Y167908D01*
G01X604525Y174159D02*
X604187Y172468D01*
G01X605437Y178719D02*
X605099Y177028D01*
G01X606348Y183279D02*
X606010Y181587D01*
G01X603614Y169600D02*
X603276Y167908D01*
G01X604525Y174159D02*
X604187Y172468D01*
G01X605437Y178719D02*
X605099Y177028D01*
G01X606348Y183279D02*
X606010Y181587D01*
G01X609207Y222563D02*
X613002Y203523D01*
G01X608298Y227123D02*
X608635Y225431D01*
G01X607389Y231684D02*
X607726Y229992D01*
G01X606480Y236244D02*
X606817Y234552D01*
G01X616492Y287751D02*
X606480Y236244D01*
G01X617648Y287272D02*
X607729Y236247D01*
G01X609207Y222563D02*
X613002Y203523D01*
G01X608298Y227123D02*
X608635Y225431D01*
G01X607389Y231684D02*
X607726Y229992D01*
G01X606480Y236244D02*
X606817Y234552D01*
G01X617648Y287272D02*
X607729Y236247D01*
G01X616492Y287751D02*
X606480Y236244D01*
G01X604224Y221229D02*
X608052Y202082D01*
G01X603312Y225789D02*
X603650Y224097D01*
G01X613390Y289710D02*
X602738Y234912D01*
G01X604224Y221229D02*
X608052Y202082D01*
G01X603312Y225789D02*
X603650Y224097D01*
G01X613390Y289710D02*
X602738Y234912D01*
G01X618447Y290648D02*
X616492Y287751D01*
G01X619328Y289763D02*
X617648Y287272D01*
G01X677157Y329791D02*
X618447Y290648D01*
G01X677635Y328637D02*
X619328Y289763D01*
G01D02*
X617648Y287272D01*
G01X618447Y290648D02*
X616492Y287751D01*
G01X677635Y328637D02*
X619328Y289763D01*
G01X677157Y329791D02*
X618447Y290648D01*
G01X614354Y293331D02*
X612234Y290189D01*
G01X615235Y292445D02*
X613390Y289710D01*
G01X675447Y334061D02*
X614354Y293331D01*
G01X675925Y332907D02*
X615235Y292445D01*
G01D02*
X613390Y289710D01*
G01X614354Y293331D02*
X612234Y290189D01*
G01X675925Y332907D02*
X615235Y292445D01*
G01X675447Y334061D02*
X614354Y293331D01*
G01X610642Y296268D02*
X608014Y292328D01*
G01X611526Y295384D02*
X609168Y291850D01*
G01X673708Y338312D02*
X610642Y296268D01*
G01X674186Y337158D02*
X611526Y295384D01*
G01D02*
X609168Y291850D01*
G01X610642Y296268D02*
X608014Y292328D01*
G01X674186Y337158D02*
X611526Y295384D01*
G01X673708Y338312D02*
X610642Y296268D01*
G01X607024Y299266D02*
X603848Y294482D01*
G01X607909Y298383D02*
X605002Y294005D01*
G01X672011Y342591D02*
X607024Y299266D01*
G01X672489Y341437D02*
X607909Y298383D01*
G01D02*
X605002Y294005D01*
G01X607024Y299266D02*
X603848Y294482D01*
G01X672489Y341437D02*
X607909Y298383D01*
G01X672011Y342591D02*
X607024Y299266D01*
G01X603548Y302359D02*
X672298Y348193D01*
G01X604432Y301475D02*
X672776Y347039D01*
G01X604432Y301475D02*
X672776Y347039D01*
G01X603548Y302359D02*
X672298Y348193D01*
G01X680644Y363113D02*
X653736Y345241D01*
G01X636915Y335541D02*
X669203Y356985D01*
G01X653736Y345241D02*
X637593Y334520D01*
G01X653736Y345241D02*
X637593Y334520D01*
G01X636915Y335541D02*
X669203Y356985D01*
G01X680644Y363113D02*
X653736Y345241D01*
G01X710823Y336526D02*
X677157Y329791D01*
G01X710823Y335276D02*
X677635Y328637D01*
G01X737359Y326488D02*
X729900Y331462D01*
G01X710823Y335276D02*
X677635Y328637D01*
G01X710823Y336526D02*
X677157Y329791D01*
G01X737359Y326488D02*
X729900Y331462D01*
G01X744112Y367117D02*
X722386Y371461D01*
G01X744112Y367117D02*
X722386Y371461D01*
G01X744112Y367117D02*
X722386Y371461D01*
G01X729218Y371345D02*
X730910Y371007D01*
G01X744112Y367117D02*
X722386Y371461D01*
G01Y372711D02*
X726350Y371919D01*
G01X744112Y367117D02*
X722386Y371461D01*
G01X680167Y364267D02*
X722386Y372711D01*
G01X701514Y367286D02*
X680644Y363113D01*
G01X722386Y371460D02*
X701514Y367286D01*
G01X669203Y356985D02*
X680167Y364267D01*
G01X669203Y356985D02*
X680167Y364267D01*
G01X701514Y367286D02*
X680644Y363113D01*
G01X680167Y364267D02*
X722386Y372711D01*
G01Y371460D02*
X701514Y367286D01*
G01X680167Y364267D02*
X722386Y372711D01*
G01X744112Y367117D02*
X722386Y371461D01*
G01X729218Y371345D02*
X730910Y371007D01*
G01X722386Y372711D02*
X726350Y371919D01*
G01X723630Y376623D02*
X744158Y372516D01*
G01X723630Y377873D02*
X734134Y375773D01*
G01X723630Y376623D02*
X744158Y372516D01*
G01X679011Y368948D02*
X723630Y377873D01*
G01X679481Y367792D02*
X723630Y376623D01*
G01D02*
X744158Y372516D01*
G01X723630Y377873D02*
X734134Y375773D01*
G01X679481Y367792D02*
X723630Y376623D01*
G01X679011Y368948D02*
X723630Y377873D01*
G01X721977Y368000D02*
X738026Y364791D01*
G01X737548Y363637D02*
X721977Y366750D01*
G01X681872Y359978D02*
X721977Y368000D01*
G01Y366750D02*
X682349Y358824D01*
G01X721977Y366750D02*
X682349Y358824D01*
G01X681872Y359978D02*
X721977Y368000D01*
G01X737548Y363637D02*
X721977Y366750D01*
G01Y368000D02*
X738026Y364791D01*
G01X730378Y332616D02*
X710823Y336526D01*
G01X729900Y331462D02*
X710823Y335276D01*
G01X738140Y327441D02*
X730378Y332616D01*
G01X729900Y331462D02*
X710823Y335276D01*
G01X730378Y332616D02*
X710823Y336526D01*
G01X738140Y327441D02*
X730378Y332616D01*
G01X710843Y341142D02*
X675447Y334061D01*
G01X710843Y339892D02*
X675925Y332907D01*
G01X733482Y336614D02*
X710843Y341142D01*
G01X733003Y335460D02*
X710843Y339892D01*
G01X741640Y331176D02*
X733482Y336614D01*
G01X740859Y330223D02*
X733004Y335460D01*
G01X710843Y339892D02*
X675925Y332907D01*
G01X710843Y341142D02*
X675447Y334061D01*
G01X733003Y335460D02*
X710843Y339892D01*
G01X733482Y336614D02*
X710843Y341142D01*
G01X740859Y330223D02*
X733004Y335460D01*
G01X741640Y331176D02*
X733482Y336614D01*
G01X712416Y346054D02*
X673708Y338312D01*
G01X712418Y344805D02*
X674186Y337158D01*
G01X742786Y340084D02*
X712416Y346054D01*
G01X742310Y338929D02*
X712418Y344805D01*
G01D02*
X674186Y337158D01*
G01X712416Y346054D02*
X673708Y338312D01*
G01X742310Y338929D02*
X712418Y344805D01*
G01X742786Y340084D02*
X712416Y346054D01*
G01X690432Y346277D02*
X672011Y342591D01*
G01X713231Y349588D02*
X672489Y341437D01*
G01X694992Y347189D02*
X693301Y346851D01*
G01X713231Y349588D02*
X672489Y341437D01*
G01X699552Y348101D02*
X697861Y347763D01*
G01X713231Y349588D02*
X672489Y341437D01*
G01X704112Y349013D02*
X702420Y348675D01*
G01X713231Y349588D02*
X672489Y341437D01*
G01X708671Y349926D02*
X706980Y349587D01*
G01X713231Y349588D02*
X672489Y341437D01*
G01X713231Y350838D02*
X711540Y350500D01*
G01X713231Y349588D02*
X672489Y341437D01*
G01X727279Y348028D02*
X713231Y350838D01*
G01X745005Y343232D02*
X713231Y349588D01*
G01X731839Y347116D02*
X730148Y347454D01*
G01X745005Y343232D02*
X713231Y349588D01*
G01X745005Y343232D02*
X713231Y349588D01*
G01X745005Y343232D02*
X713231Y349588D01*
G01X745005Y343232D02*
X713231Y349588D01*
G01D02*
X672489Y341437D01*
G01X690432Y346277D02*
X672011Y342591D01*
G01X694992Y347189D02*
X693301Y346851D01*
G01X699552Y348101D02*
X697861Y347763D01*
G01X704112Y349013D02*
X702420Y348675D01*
G01X708671Y349926D02*
X706980Y349587D01*
G01X713231Y350838D02*
X711540Y350500D01*
G01X745005Y343232D02*
X713231Y349588D01*
G01X727279Y348028D02*
X713231Y350838D01*
G01X731839Y347116D02*
X730148Y347454D01*
G01X727426Y357967D02*
X739885Y355476D01*
G01X727426Y357967D02*
X739885Y355476D01*
G01X727426Y359217D02*
X731243Y358454D01*
G01X727426Y357967D02*
X739885Y355476D01*
G01X725734Y358879D02*
X727426Y359217D01*
G01X672776Y347039D02*
X727426Y357967D01*
G01X721174D02*
X722866Y358305D01*
G01X672776Y347039D02*
X727426Y357967D01*
G01X716614Y357055D02*
X718306Y357393D01*
G01X672776Y347039D02*
X727426Y357967D01*
G01X712054Y356143D02*
X713746Y356481D01*
G01X672776Y347039D02*
X727426Y357967D01*
G01X687934Y351320D02*
X709186Y355570D01*
G01X672776Y347039D02*
X727426Y357967D01*
G01X683374Y350408D02*
X685066Y350746D01*
G01X672776Y347039D02*
X727426Y357967D01*
G01X678814Y349496D02*
X680506Y349834D01*
G01X672776Y347039D02*
X727426Y357967D01*
G01X673386Y348411D02*
X675945Y348922D01*
G01X672776Y347039D02*
X727426Y357967D01*
G01X672298Y348193D02*
X673386Y348411D01*
G01X672776Y347039D02*
X727426Y357967D01*
G01D02*
X739885Y355476D01*
G01X727426Y359217D02*
X731243Y358454D01*
G01X672776Y347039D02*
X727426Y357967D01*
G01X725734Y358879D02*
X727426Y359217D01*
G01X721174Y357967D02*
X722866Y358305D01*
G01X716614Y357055D02*
X718306Y357393D01*
G01X712054Y356143D02*
X713746Y356481D01*
G01X687934Y351320D02*
X709186Y355570D01*
G01X683374Y350408D02*
X685066Y350746D01*
G01X678814Y349496D02*
X680506Y349834D01*
G01X673386Y348411D02*
X675945Y348922D01*
G01X672298Y348193D02*
X673386Y348411D01*
G01X788341Y305458D02*
Y317924D01*
G01X787116Y305966D02*
Y317901D01*
G01X786341Y303458D02*
X788341Y305458D01*
G01X785475Y304325D02*
X787116Y305966D01*
G01D02*
Y317901D01*
G01X788341Y305458D02*
Y317924D01*
G01X785475Y304325D02*
X787116Y305966D01*
G01X786341Y303458D02*
X788341Y305458D01*
G01X793341Y306208D02*
X788367Y301234D01*
G01X792116Y306716D02*
X787500Y302100D01*
G01X793341Y317924D02*
Y306208D01*
G01X792116Y317901D02*
Y306716D01*
G01D02*
X787500Y302100D01*
G01X793341Y306208D02*
X788367Y301234D01*
G01X792116Y317901D02*
Y306716D01*
G01X793341Y317924D02*
Y306208D01*
G01X741734Y315266D02*
Y317817D01*
G01X740509Y314758D02*
Y318008D01*
G01X744855Y312145D02*
X741734Y315266D01*
G01X744347Y310920D02*
X740509Y314758D01*
G01X746255Y312145D02*
X744855D01*
G01X745747Y310920D02*
X744347D01*
G01X754385Y304015D02*
X746255Y312145D01*
G01X745747Y310920D02*
X744347D01*
G01X753160Y303507D02*
X745747Y310920D01*
G01X754385Y298625D02*
Y304015D01*
G01X753160Y298625D02*
Y303507D01*
G01X740509Y314758D02*
Y318008D01*
G01X741734Y315266D02*
Y317817D01*
G01X744347Y310920D02*
X740509Y314758D01*
G01X744855Y312145D02*
X741734Y315266D01*
G01X745747Y310920D02*
X744347D01*
G01X746255Y312145D02*
X744855D01*
G01X754385Y304015D02*
X746255Y312145D01*
G01X753160Y303507D02*
X745747Y310920D01*
G01X754385Y304015D02*
X746255Y312145D01*
G01X753160Y298625D02*
Y303507D01*
G01X754385Y298625D02*
Y304015D01*
G01X748343Y314511D02*
Y317926D01*
G01X747118Y314002D02*
Y317899D01*
G01X755975Y306879D02*
X748343Y314511D01*
G01X755108Y306012D02*
X747118Y314002D01*
G01D02*
Y317899D01*
G01X748343Y314511D02*
Y317926D01*
G01X755108Y306012D02*
X747118Y314002D01*
G01X755975Y306879D02*
X748343Y314511D01*
G01X756416Y312734D02*
Y317999D01*
G01X755191Y312226D02*
Y317826D01*
G01X764385Y304765D02*
X756416Y312734D01*
G01X763160Y304257D02*
X755191Y312226D01*
G01X764385Y301675D02*
Y304765D01*
G01X763160Y301675D02*
Y304257D01*
G01X755191Y312226D02*
Y317826D01*
G01X756416Y312734D02*
Y317999D01*
G01X763160Y304257D02*
X755191Y312226D01*
G01X764385Y304765D02*
X756416Y312734D01*
G01X763160Y301675D02*
Y304257D01*
G01X764385Y301675D02*
Y304765D01*
G01X761335Y314965D02*
Y317918D01*
G01X760110Y314457D02*
Y317908D01*
G01X767550Y308750D02*
X761335Y314965D01*
G01X766325Y308242D02*
X760110Y314457D01*
G01X767550Y306000D02*
Y308750D01*
G01X766325Y306000D02*
Y308242D01*
G01X760110Y314457D02*
Y317908D01*
G01X761335Y314965D02*
Y317918D01*
G01X766325Y308242D02*
X760110Y314457D01*
G01X767550Y308750D02*
X761335Y314965D01*
G01X766325Y306000D02*
Y308242D01*
G01X767550Y306000D02*
Y308750D01*
G01X778341Y313108D02*
Y317924D01*
G01X777116Y313616D02*
Y317901D01*
G01X775385Y310152D02*
X778341Y313108D01*
G01X774160Y310660D02*
X777116Y313616D01*
G01X775385Y302275D02*
Y310152D01*
G01X774160Y302275D02*
Y310660D01*
G01X777116Y313616D02*
Y317901D01*
G01X778341Y313108D02*
Y317924D01*
G01X774160Y310660D02*
X777116Y313616D01*
G01X775385Y310152D02*
X778341Y313108D01*
G01X774160Y302275D02*
Y310660D01*
G01X775385Y302275D02*
Y310152D01*
G01X783341Y305991D02*
Y317924D01*
G01X782116Y306499D02*
Y317901D01*
G01X779800Y302450D02*
X783341Y305991D01*
G01X778575Y302958D02*
X782116Y306499D01*
G01X779800Y300969D02*
Y302450D01*
G01X778575Y300969D02*
Y302958D01*
G01X782116Y306499D02*
Y317901D01*
G01X783341Y305991D02*
Y317924D01*
G01X778575Y302958D02*
X782116Y306499D01*
G01X779800Y302450D02*
X783341Y305991D01*
G01X778575Y300969D02*
Y302958D01*
G01X779800Y300969D02*
Y302450D01*
G01X788362Y331639D02*
Y321055D01*
G01X787137Y321120D02*
Y331131D01*
G01Y321120D02*
Y331131D01*
G01X788362Y331639D02*
Y321055D01*
G01X793309Y333192D02*
Y321107D01*
G01X792084Y332684D02*
Y321067D01*
G01Y332684D02*
Y321067D01*
G01X793309Y333192D02*
Y321107D01*
G01X783326Y325674D02*
Y321091D01*
G01X782101Y321083D02*
Y325166D01*
G01X756581Y352420D02*
X783326Y325674D01*
G01X782101Y325166D02*
X755800Y351467D01*
G01X782101Y325166D02*
X755800Y351467D01*
G01X756581Y352420D02*
X783326Y325674D01*
G01X782101Y321083D02*
Y325166D01*
G01X783326Y325674D02*
Y321091D01*
G01X741843Y323738D02*
X738140Y327441D01*
G01X740618Y323230D02*
X737359Y326488D01*
G01X741843Y321074D02*
Y323738D01*
G01X740618Y321101D02*
Y323230D01*
G01D02*
X737359Y326488D01*
G01X741843Y323738D02*
X738140Y327441D01*
G01X740618Y321101D02*
Y323230D01*
G01X741843Y321074D02*
Y323738D01*
G01X748318Y324498D02*
X741640Y331176D01*
G01X747093Y323990D02*
X740859Y330223D01*
G01X748318Y321099D02*
Y324498D01*
G01X747093Y321076D02*
Y323990D01*
G01D02*
X740859Y330223D01*
G01X748318Y324498D02*
X741640Y331176D01*
G01X747093Y321076D02*
Y323990D01*
G01X748318Y321099D02*
Y324498D01*
G01X756300Y328616D02*
X748922Y335994D01*
G01X755075Y328108D02*
X748141Y335041D01*
G01X756300Y321117D02*
Y328616D01*
G01X755075Y321058D02*
Y328108D01*
G01D02*
X748141Y335041D01*
G01X756300Y328616D02*
X748922Y335994D01*
G01X755075Y321058D02*
Y328108D01*
G01X756300Y321117D02*
Y328616D01*
G01X760093Y329490D02*
X750388Y339195D01*
G01X760093Y329490D02*
X750388Y339195D01*
G01X760093Y329490D02*
X750388Y339195D01*
G01X760093Y329490D02*
X750388Y339195D01*
G01X761318Y329998D02*
X760098Y331218D01*
G01X760093Y329490D02*
X750388Y339195D01*
G01X761318Y321099D02*
Y329998D01*
G01X760093Y321076D02*
Y329490D01*
G01D02*
X750388Y339195D01*
G01X761318Y329998D02*
X760098Y331218D01*
G01X760093Y321076D02*
Y329490D01*
G01X761318Y321099D02*
Y329998D01*
G01X778318Y324097D02*
Y321099D01*
G01X777093Y323589D02*
Y321076D01*
G01X756625Y345791D02*
X778318Y324097D01*
G01X755844Y344838D02*
X777093Y323589D01*
G01D02*
Y321076D01*
G01X778318Y324097D02*
Y321099D01*
G01X755844Y344838D02*
X777093Y323589D01*
G01X756625Y345791D02*
X778318Y324097D01*
G01X766008Y353994D02*
X788362Y331639D01*
G01X787137Y331131D02*
X765227Y353041D01*
G01X744590Y368271D02*
X766008Y353994D01*
G01X765227Y353041D02*
X744112Y367117D01*
G01X742898Y368609D02*
X744590Y368271D01*
G01X738338Y369521D02*
X740030Y369183D01*
G01X733778Y370433D02*
X735470Y370095D01*
G01X742898Y368609D02*
X744590Y368271D01*
G01X738338Y369521D02*
X740030Y369183D01*
G01X733778Y370433D02*
X735470Y370095D01*
G01X765227Y353041D02*
X744112Y367117D01*
G01X744590Y368271D02*
X766008Y353994D01*
G01X787137Y331131D02*
X765227Y353041D01*
G01X766008Y353994D02*
X788362Y331639D01*
G01X769220Y357282D02*
X793309Y333192D01*
G01X768439Y356329D02*
X792084Y332684D01*
G01X758557Y364390D02*
X769220Y357282D01*
G01X744158Y372516D02*
X768439Y356329D01*
G01X756123Y366013D02*
X756955Y366179D01*
G01X744158Y372516D02*
X768439Y356329D01*
G01X754688Y366969D02*
X756123Y366013D01*
G01X744158Y372516D02*
X768439Y356329D01*
G01X752254Y368592D02*
X753086Y368758D01*
G01X744158Y372516D02*
X768439Y356329D01*
G01X750819Y369549D02*
X752254Y368592D01*
G01X744158Y372516D02*
X768439Y356329D01*
G01X744636Y373670D02*
X748385Y371171D01*
G01X744158Y372516D02*
X768439Y356329D01*
G01X734134Y375773D02*
X744636Y373670D01*
G01X768439Y356329D02*
X792084Y332684D01*
G01X769220Y357282D02*
X793309Y333192D01*
G01X744158Y372516D02*
X768439Y356329D01*
G01X758557Y364390D02*
X769220Y357282D01*
G01X756123Y366013D02*
X756955Y366179D01*
G01X754688Y366969D02*
X756123Y366013D01*
G01X752254Y368592D02*
X753086Y368758D01*
G01X750819Y369549D02*
X752254Y368592D01*
G01X744636Y373670D02*
X748385Y371171D01*
G01X734134Y375773D02*
X744636Y373670D01*
G01X751277Y355956D02*
X756581Y352420D01*
G01X755800Y351467D02*
X737548Y363637D01*
G01X748843Y357579D02*
X749675Y357745D01*
G01X755800Y351467D02*
X737548Y363637D01*
G01X747408Y358536D02*
X748843Y357579D01*
G01X755800Y351467D02*
X737548Y363637D01*
G01X743539Y361115D02*
X744974Y360158D01*
G01X755800Y351467D02*
X737548Y363637D01*
G01X741105Y362738D02*
X741937Y362904D01*
G01X755800Y351467D02*
X737548Y363637D01*
G01X738026Y364791D02*
X741105Y362738D01*
G01X755800Y351467D02*
X737548Y363637D01*
G01X755800Y351467D02*
X737548Y363637D01*
G01X751277Y355956D02*
X756581Y352420D01*
G01X748843Y357579D02*
X749675Y357745D01*
G01X747408Y358536D02*
X748843Y357579D01*
G01X743539Y361115D02*
X744974Y360158D01*
G01X741105Y362738D02*
X741937Y362904D01*
G01X738026Y364791D02*
X741105Y362738D01*
G01X748922Y335994D02*
X742786Y340084D01*
G01X748141Y335041D02*
X742310Y338929D01*
G01X748141Y335041D02*
X742310Y338929D01*
G01X748922Y335994D02*
X742786Y340084D01*
G01X736399Y346203D02*
X734707Y346542D01*
G01X740958Y345291D02*
X739267Y345630D01*
G01X745518Y344379D02*
X743827Y344717D01*
G01X751193Y340123D02*
X745518Y344379D01*
G01X750388Y339195D02*
X745005Y343232D01*
G01X754742Y336574D02*
X751193Y340123D01*
G01X755590Y336574D02*
X754742D01*
G01X758030Y333286D02*
X756810Y334506D01*
G01X758878Y333286D02*
X758030D01*
G01X736399Y346203D02*
X734707Y346542D01*
G01X740958Y345291D02*
X739267Y345630D01*
G01X745518Y344379D02*
X743827Y344717D01*
G01X750388Y339195D02*
X745005Y343232D01*
G01X751193Y340123D02*
X745518Y344379D01*
G01X754742Y336574D02*
X751193Y340123D01*
G01X755590Y336574D02*
X754742D01*
G01X758030Y333286D02*
X756810Y334506D01*
G01X758878Y333286D02*
X758030D01*
G01X755190Y346748D02*
X756625Y345791D01*
G01X739885Y355476D02*
X755844Y344838D01*
G01X752756Y348370D02*
X753588Y348536D01*
G01X739885Y355476D02*
X755844Y344838D01*
G01X751321Y349327D02*
X752756Y348370D01*
G01X739885Y355476D02*
X755844Y344838D01*
G01X748887Y350949D02*
X749719Y351115D01*
G01X739885Y355476D02*
X755844Y344838D01*
G01X747452Y351906D02*
X748887Y350949D01*
G01X739885Y355476D02*
X755844Y344838D01*
G01X745018Y353528D02*
X745850Y353694D01*
G01X739885Y355476D02*
X755844Y344838D01*
G01X740363Y356630D02*
X745018Y353528D01*
G01X739885Y355476D02*
X755844Y344838D01*
G01X738671Y356968D02*
X740363Y356630D01*
G01X734111Y357880D02*
X735803Y357542D01*
G01X739885Y355476D02*
X755844Y344838D01*
G01X755190Y346748D02*
X756625Y345791D01*
G01X752756Y348370D02*
X753588Y348536D01*
G01X751321Y349327D02*
X752756Y348370D01*
G01X748887Y350949D02*
X749719Y351115D01*
G01X747452Y351906D02*
X748887Y350949D01*
G01X745018Y353528D02*
X745850Y353694D01*
G01X740363Y356630D02*
X745018Y353528D01*
G01X738671Y356968D02*
X740363Y356630D01*
G01X734111Y357880D02*
X735803Y357542D01*
M02*
